(kicad_sch
	(version 20250114)
	(generator "eeschema")
	(generator_version "9.0")
	(paper "A3")
	(title_block
		(title "SO-DIMM DDR5 Tester")
		(date "2025-11-26")
		(rev "1.3.0")
		(company "Antmicro Ltd.")
		(comment 1 "www.antmicro.com")
		(comment 2 "Antmicro Ltd")
	)
	(text "Mount 3K4 for LPDDR5"
		(exclude_from_sim no)
		(at 35.56 245.11 0)
		(effects
			(font
				(size 1.27 1.27)
			)
			(justify left bottom)
		)
	)
	(text "BANK 34"
		(exclude_from_sim no)
		(at 327.66 43.18 0)
		(effects
			(font
				(size 1.27 1.27)
				(thickness 0.4978)
				(bold yes)
			)
			(justify left bottom)
		)
	)
	(text "BANK 33"
		(exclude_from_sim no)
		(at 224.79 43.815 0)
		(effects
			(font
				(size 1.27 1.27)
				(thickness 0.4978)
				(bold yes)
			)
			(justify left bottom)
		)
	)
	(text "VCCO (HP banks) max: 2.0V"
		(exclude_from_sim no)
		(at 13.97 20.955 0)
		(effects
			(font
				(size 1.27 1.27)
			)
			(justify left bottom)
		)
	)
	(text "Reference termination"
		(exclude_from_sim no)
		(at 111.76 227.33 0)
		(effects
			(font
				(size 2.54 2.54)
				(thickness 0.4978)
				(bold yes)
			)
			(justify left bottom)
		)
	)
	(text "HP Banks"
		(exclude_from_sim no)
		(at 13.335 18.415 0)
		(effects
			(font
				(size 2.54 2.54)
				(thickness 0.4978)
				(bold yes)
			)
			(justify left bottom)
		)
	)
	(text "BANK 32"
		(exclude_from_sim no)
		(at 91.44 42.545 0)
		(effects
			(font
				(size 1.27 1.27)
				(thickness 0.4978)
				(bold yes)
			)
			(justify left bottom)
		)
	)
	(text "Pinout D.1.1"
		(exclude_from_sim no)
		(at 394.335 220.345 0)
		(effects
			(font
				(size 1.27 1.27)
			)
			(justify left bottom)
		)
	)
	(text "VREF"
		(exclude_from_sim no)
		(at 13.335 227.33 0)
		(effects
			(font
				(size 2.54 2.54)
				(thickness 0.4978)
				(bold yes)
			)
			(justify left bottom)
		)
	)
	(junction
		(at 79.375 245.745)
		(diameter 0)
		(color 0 0 0 0)
	)
	(junction
		(at 34.29 245.745)
		(diameter 0)
		(color 0 0 0 0)
	)
	(junction
		(at 72.39 245.745)
		(diameter 0)
		(color 0 0 0 0)
	)
	(no_connect
		(at 218.44 166.37)
	)
	(no_connect
		(at 218.44 110.49)
	)
	(bus_entry
		(at 78.105 115.57)
		(size -2.54 -2.54)
		(stroke
			(width 0)
			(type default)
		)
	)
	(bus_entry
		(at 307.34 189.23)
		(size -2.54 -2.54)
		(stroke
			(width 0)
			(type default)
		)
	)
	(bus_entry
		(at 170.815 124.46)
		(size 1.27 1.27)
		(stroke
			(width 0)
			(type default)
		)
	)
	(bus_entry
		(at 170.815 137.16)
		(size 1.27 1.27)
		(stroke
			(width 0)
			(type default)
		)
	)
	(bus_entry
		(at 307.34 123.19)
		(size -2.54 -2.54)
		(stroke
			(width 0)
			(type default)
		)
	)
	(bus_entry
		(at 307.34 148.59)
		(size -2.54 -2.54)
		(stroke
			(width 0)
			(type default)
		)
	)
	(bus_entry
		(at 184.785 99.06)
		(size 1.27 1.27)
		(stroke
			(width 0)
			(type default)
		)
	)
	(bus_entry
		(at 78.105 97.79)
		(size -2.54 -2.54)
		(stroke
			(width 0)
			(type default)
		)
	)
	(bus_entry
		(at 307.34 143.51)
		(size -2.54 -2.54)
		(stroke
			(width 0)
			(type default)
		)
	)
	(bus_entry
		(at 307.34 120.65)
		(size -2.54 -2.54)
		(stroke
			(width 0)
			(type default)
		)
	)
	(bus_entry
		(at 307.34 67.31)
		(size -2.54 -2.54)
		(stroke
			(width 0)
			(type default)
		)
	)
	(bus_entry
		(at 78.105 143.51)
		(size -2.54 -2.54)
		(stroke
			(width 0)
			(type default)
		)
	)
	(bus_entry
		(at 78.105 123.19)
		(size -2.54 -2.54)
		(stroke
			(width 0)
			(type default)
		)
	)
	(bus_entry
		(at 78.105 120.65)
		(size -2.54 -2.54)
		(stroke
			(width 0)
			(type default)
		)
	)
	(bus_entry
		(at 78.105 181.61)
		(size -2.54 -2.54)
		(stroke
			(width 0)
			(type default)
		)
	)
	(bus_entry
		(at 184.785 96.52)
		(size 1.27 1.27)
		(stroke
			(width 0)
			(type default)
		)
	)
	(bus_entry
		(at 78.105 128.27)
		(size -2.54 -2.54)
		(stroke
			(width 0)
			(type default)
		)
	)
	(bus_entry
		(at 78.105 176.53)
		(size -2.54 -2.54)
		(stroke
			(width 0)
			(type default)
		)
	)
	(bus_entry
		(at 184.785 91.44)
		(size 1.27 1.27)
		(stroke
			(width 0)
			(type default)
		)
	)
	(bus_entry
		(at 307.34 110.49)
		(size -2.54 -2.54)
		(stroke
			(width 0)
			(type default)
		)
	)
	(bus_entry
		(at 184.785 76.2)
		(size 1.27 1.27)
		(stroke
			(width 0)
			(type default)
		)
	)
	(bus_entry
		(at 170.815 162.56)
		(size 1.27 1.27)
		(stroke
			(width 0)
			(type default)
		)
	)
	(bus_entry
		(at 78.105 148.59)
		(size -2.54 -2.54)
		(stroke
			(width 0)
			(type default)
		)
	)
	(bus_entry
		(at 78.105 74.93)
		(size -2.54 -2.54)
		(stroke
			(width 0)
			(type default)
		)
	)
	(bus_entry
		(at 307.34 168.91)
		(size -2.54 -2.54)
		(stroke
			(width 0)
			(type default)
		)
	)
	(bus_entry
		(at 78.105 100.33)
		(size -2.54 -2.54)
		(stroke
			(width 0)
			(type default)
		)
	)
	(bus_entry
		(at 307.34 176.53)
		(size -2.54 -2.54)
		(stroke
			(width 0)
			(type default)
		)
	)
	(bus_entry
		(at 78.105 179.07)
		(size -2.54 -2.54)
		(stroke
			(width 0)
			(type default)
		)
	)
	(bus_entry
		(at 170.815 170.18)
		(size 1.27 1.27)
		(stroke
			(width 0)
			(type default)
		)
	)
	(bus_entry
		(at 78.105 189.23)
		(size -2.54 -2.54)
		(stroke
			(width 0)
			(type default)
		)
	)
	(bus_entry
		(at 307.34 105.41)
		(size -2.54 -2.54)
		(stroke
			(width 0)
			(type default)
		)
	)
	(bus_entry
		(at 307.34 156.21)
		(size -2.54 -2.54)
		(stroke
			(width 0)
			(type default)
		)
	)
	(bus_entry
		(at 307.34 171.45)
		(size -2.54 -2.54)
		(stroke
			(width 0)
			(type default)
		)
	)
	(bus_entry
		(at 184.785 177.8)
		(size 1.27 1.27)
		(stroke
			(width 0)
			(type default)
		)
	)
	(bus_entry
		(at 184.785 68.58)
		(size 1.27 1.27)
		(stroke
			(width 0)
			(type default)
		)
	)
	(bus_entry
		(at 307.34 181.61)
		(size -2.54 -2.54)
		(stroke
			(width 0)
			(type default)
		)
	)
	(bus_entry
		(at 307.34 115.57)
		(size -2.54 -2.54)
		(stroke
			(width 0)
			(type default)
		)
	)
	(bus_entry
		(at 170.815 157.48)
		(size 1.27 1.27)
		(stroke
			(width 0)
			(type default)
		)
	)
	(bus_entry
		(at 307.34 64.77)
		(size -2.54 -2.54)
		(stroke
			(width 0)
			(type default)
		)
	)
	(bus_entry
		(at 307.34 118.11)
		(size -2.54 -2.54)
		(stroke
			(width 0)
			(type default)
		)
	)
	(bus_entry
		(at 198.755 185.42)
		(size 1.27 1.27)
		(stroke
			(width 0)
			(type default)
		)
	)
	(bus_entry
		(at 184.785 154.94)
		(size 1.27 1.27)
		(stroke
			(width 0)
			(type default)
		)
	)
	(bus_entry
		(at 184.785 182.88)
		(size 1.27 1.27)
		(stroke
			(width 0)
			(type default)
		)
	)
	(bus_entry
		(at 307.34 74.93)
		(size -2.54 -2.54)
		(stroke
			(width 0)
			(type default)
		)
	)
	(bus_entry
		(at 184.785 66.04)
		(size 1.27 1.27)
		(stroke
			(width 0)
			(type default)
		)
	)
	(bus_entry
		(at 184.785 86.36)
		(size 1.27 1.27)
		(stroke
			(width 0)
			(type default)
		)
	)
	(bus_entry
		(at 170.815 116.84)
		(size 1.27 1.27)
		(stroke
			(width 0)
			(type default)
		)
	)
	(bus_entry
		(at 78.105 85.09)
		(size -2.54 -2.54)
		(stroke
			(width 0)
			(type default)
		)
	)
	(bus_entry
		(at 78.105 90.17)
		(size -2.54 -2.54)
		(stroke
			(width 0)
			(type default)
		)
	)
	(bus_entry
		(at 78.105 69.85)
		(size -2.54 -2.54)
		(stroke
			(width 0)
			(type default)
		)
	)
	(bus_entry
		(at 307.34 128.27)
		(size -2.54 -2.54)
		(stroke
			(width 0)
			(type default)
		)
	)
	(bus_entry
		(at 170.815 104.14)
		(size 1.27 1.27)
		(stroke
			(width 0)
			(type default)
		)
	)
	(bus_entry
		(at 184.785 132.08)
		(size 1.27 1.27)
		(stroke
			(width 0)
			(type default)
		)
	)
	(bus_entry
		(at 198.755 149.86)
		(size 1.27 1.27)
		(stroke
			(width 0)
			(type default)
		)
	)
	(bus_entry
		(at 307.34 146.05)
		(size -2.54 -2.54)
		(stroke
			(width 0)
			(type default)
		)
	)
	(bus_entry
		(at 307.34 130.81)
		(size -2.54 -2.54)
		(stroke
			(width 0)
			(type default)
		)
	)
	(bus_entry
		(at 170.815 144.78)
		(size 1.27 1.27)
		(stroke
			(width 0)
			(type default)
		)
	)
	(bus_entry
		(at 78.105 67.31)
		(size -2.54 -2.54)
		(stroke
			(width 0)
			(type default)
		)
	)
	(bus_entry
		(at 78.1174 133.35)
		(size -2.54 -2.54)
		(stroke
			(width 0)
			(type default)
		)
	)
	(bus_entry
		(at 78.105 173.99)
		(size -2.54 -2.54)
		(stroke
			(width 0)
			(type default)
		)
	)
	(bus_entry
		(at 307.34 153.67)
		(size -2.54 -2.54)
		(stroke
			(width 0)
			(type default)
		)
	)
	(bus_entry
		(at 78.105 140.97)
		(size -2.54 -2.54)
		(stroke
			(width 0)
			(type default)
		)
	)
	(bus_entry
		(at 78.105 82.55)
		(size -2.54 -2.54)
		(stroke
			(width 0)
			(type default)
		)
	)
	(bus_entry
		(at 78.105 105.41)
		(size -2.54 -2.54)
		(stroke
			(width 0)
			(type default)
		)
	)
	(bus_entry
		(at 78.105 102.87)
		(size -2.54 -2.54)
		(stroke
			(width 0)
			(type default)
		)
	)
	(bus_entry
		(at 78.105 146.05)
		(size -2.54 -2.54)
		(stroke
			(width 0)
			(type default)
		)
	)
	(bus_entry
		(at 170.815 175.26)
		(size 1.27 1.27)
		(stroke
			(width 0)
			(type default)
		)
	)
	(bus_entry
		(at 307.34 82.55)
		(size -2.54 -2.54)
		(stroke
			(width 0)
			(type default)
		)
	)
	(bus_entry
		(at 307.34 69.85)
		(size -2.54 -2.54)
		(stroke
			(width 0)
			(type default)
		)
	)
	(bus_entry
		(at 307.34 133.35)
		(size -2.54 -2.54)
		(stroke
			(width 0)
			(type default)
		)
	)
	(bus_entry
		(at 307.34 166.37)
		(size -2.54 -2.54)
		(stroke
			(width 0)
			(type default)
		)
	)
	(bus_entry
		(at 307.34 186.69)
		(size -2.54 -2.54)
		(stroke
			(width 0)
			(type default)
		)
	)
	(bus_entry
		(at 307.34 77.47)
		(size -2.54 -2.54)
		(stroke
			(width 0)
			(type default)
		)
	)
	(bus_entry
		(at 78.105 171.45)
		(size -2.54 -2.54)
		(stroke
			(width 0)
			(type default)
		)
	)
	(bus_entry
		(at 307.34 97.79)
		(size -2.54 -2.54)
		(stroke
			(width 0)
			(type default)
		)
	)
	(bus_entry
		(at 307.34 173.99)
		(size -2.54 -2.54)
		(stroke
			(width 0)
			(type default)
		)
	)
	(bus_entry
		(at 170.815 127)
		(size 1.27 1.27)
		(stroke
			(width 0)
			(type default)
		)
	)
	(bus_entry
		(at 307.34 87.63)
		(size -2.54 -2.54)
		(stroke
			(width 0)
			(type default)
		)
	)
	(bus_entry
		(at 78.105 92.71)
		(size -2.54 -2.54)
		(stroke
			(width 0)
			(type default)
		)
	)
	(bus_entry
		(at 307.34 158.75)
		(size -2.54 -2.54)
		(stroke
			(width 0)
			(type default)
		)
	)
	(bus_entry
		(at 184.785 71.12)
		(size 1.27 1.27)
		(stroke
			(width 0)
			(type default)
		)
	)
	(bus_entry
		(at 307.34 151.13)
		(size -2.54 -2.54)
		(stroke
			(width 0)
			(type default)
		)
	)
	(bus_entry
		(at 78.105 110.49)
		(size -2.54 -2.54)
		(stroke
			(width 0)
			(type default)
		)
	)
	(bus_entry
		(at 184.785 142.24)
		(size 1.27 1.27)
		(stroke
			(width 0)
			(type default)
		)
	)
	(bus_entry
		(at 307.34 138.43)
		(size -2.54 -2.54)
		(stroke
			(width 0)
			(type default)
		)
	)
	(bus_entry
		(at 170.815 147.32)
		(size 1.27 1.27)
		(stroke
			(width 0)
			(type default)
		)
	)
	(bus_entry
		(at 307.34 125.73)
		(size -2.54 -2.54)
		(stroke
			(width 0)
			(type default)
		)
	)
	(bus_entry
		(at 184.785 73.66)
		(size 1.27 1.27)
		(stroke
			(width 0)
			(type default)
		)
	)
	(bus_entry
		(at 307.34 85.09)
		(size -2.54 -2.54)
		(stroke
			(width 0)
			(type default)
		)
	)
	(bus_entry
		(at 307.34 179.07)
		(size -2.54 -2.54)
		(stroke
			(width 0)
			(type default)
		)
	)
	(bus_entry
		(at 78.105 166.37)
		(size -2.54 -2.54)
		(stroke
			(width 0)
			(type default)
		)
	)
	(bus_entry
		(at 184.785 88.9)
		(size 1.27 1.27)
		(stroke
			(width 0)
			(type default)
		)
	)
	(bus_entry
		(at 170.815 119.38)
		(size 1.27 1.27)
		(stroke
			(width 0)
			(type default)
		)
	)
	(bus_entry
		(at 184.785 78.74)
		(size 1.27 1.27)
		(stroke
			(width 0)
			(type default)
		)
	)
	(bus_entry
		(at 78.105 163.83)
		(size -2.54 -2.54)
		(stroke
			(width 0)
			(type default)
		)
	)
	(bus_entry
		(at 78.105 138.43)
		(size -2.54 -2.54)
		(stroke
			(width 0)
			(type default)
		)
	)
	(bus_entry
		(at 78.105 77.47)
		(size -2.54 -2.54)
		(stroke
			(width 0)
			(type default)
		)
	)
	(bus_entry
		(at 170.815 167.64)
		(size 1.27 1.27)
		(stroke
			(width 0)
			(type default)
		)
	)
	(bus_entry
		(at 78.105 72.39)
		(size -2.54 -2.54)
		(stroke
			(width 0)
			(type default)
		)
	)
	(bus_entry
		(at 170.815 139.7)
		(size 1.27 1.27)
		(stroke
			(width 0)
			(type default)
		)
	)
	(bus_entry
		(at 78.153 125.73)
		(size -2.54 -2.54)
		(stroke
			(width 0)
			(type default)
		)
	)
	(bus_entry
		(at 170.815 111.76)
		(size 1.27 1.27)
		(stroke
			(width 0)
			(type default)
		)
	)
	(bus_entry
		(at 307.34 100.33)
		(size -2.54 -2.54)
		(stroke
			(width 0)
			(type default)
		)
	)
	(bus_entry
		(at 184.785 83.82)
		(size 1.27 1.27)
		(stroke
			(width 0)
			(type default)
		)
	)
	(bus_entry
		(at 307.34 90.17)
		(size -2.54 -2.54)
		(stroke
			(width 0)
			(type default)
		)
	)
	(bus_entry
		(at 184.785 180.34)
		(size 1.27 1.27)
		(stroke
			(width 0)
			(type default)
		)
	)
	(bus_entry
		(at 170.815 101.6)
		(size 1.27 1.27)
		(stroke
			(width 0)
			(type default)
		)
	)
	(bus_entry
		(at 78.2242 130.81)
		(size -2.54 -2.54)
		(stroke
			(width 0)
			(type default)
		)
	)
	(bus_entry
		(at 78.105 184.15)
		(size -2.54 -2.54)
		(stroke
			(width 0)
			(type default)
		)
	)
	(bus_entry
		(at 78.105 153.67)
		(size -2.54 -2.54)
		(stroke
			(width 0)
			(type default)
		)
	)
	(bus_entry
		(at 307.34 102.87)
		(size -2.54 -2.54)
		(stroke
			(width 0)
			(type default)
		)
	)
	(bus_entry
		(at 184.785 134.62)
		(size 1.27 1.27)
		(stroke
			(width 0)
			(type default)
		)
	)
	(bus_entry
		(at 78.105 156.21)
		(size -2.54 -2.54)
		(stroke
			(width 0)
			(type default)
		)
	)
	(bus_entry
		(at 307.34 113.03)
		(size -2.54 -2.54)
		(stroke
			(width 0)
			(type default)
		)
	)
	(bus_entry
		(at 184.785 81.28)
		(size 1.27 1.27)
		(stroke
			(width 0)
			(type default)
		)
	)
	(bus_entry
		(at 78.105 186.69)
		(size -2.54 -2.54)
		(stroke
			(width 0)
			(type default)
		)
	)
	(bus_entry
		(at 307.34 140.97)
		(size -2.54 -2.54)
		(stroke
			(width 0)
			(type default)
		)
	)
	(bus_entry
		(at 78.105 118.11)
		(size -2.54 -2.54)
		(stroke
			(width 0)
			(type default)
		)
	)
	(bus_entry
		(at 184.785 152.4)
		(size 1.27 1.27)
		(stroke
			(width 0)
			(type default)
		)
	)
	(bus_entry
		(at 307.34 163.83)
		(size -2.54 -2.54)
		(stroke
			(width 0)
			(type default)
		)
	)
	(bus_entry
		(at 78.105 80.01)
		(size -2.54 -2.54)
		(stroke
			(width 0)
			(type default)
		)
	)
	(bus_entry
		(at 307.34 92.71)
		(size -2.54 -2.54)
		(stroke
			(width 0)
			(type default)
		)
	)
	(bus_entry
		(at 307.34 184.15)
		(size -2.54 -2.54)
		(stroke
			(width 0)
			(type default)
		)
	)
	(bus_entry
		(at 78.105 107.95)
		(size -2.54 -2.54)
		(stroke
			(width 0)
			(type default)
		)
	)
	(bus_entry
		(at 78.105 135.89)
		(size -2.54 -2.54)
		(stroke
			(width 0)
			(type default)
		)
	)
	(bus_entry
		(at 307.34 72.39)
		(size -2.54 -2.54)
		(stroke
			(width 0)
			(type default)
		)
	)
	(bus_entry
		(at 78.105 151.13)
		(size -2.54 -2.54)
		(stroke
			(width 0)
			(type default)
		)
	)
	(bus_entry
		(at 307.34 80.01)
		(size -2.54 -2.54)
		(stroke
			(width 0)
			(type default)
		)
	)
	(bus_entry
		(at 307.34 107.95)
		(size -2.54 -2.54)
		(stroke
			(width 0)
			(type default)
		)
	)
	(bus_entry
		(at 170.815 121.92)
		(size 1.27 1.27)
		(stroke
			(width 0)
			(type default)
		)
	)
	(bus_entry
		(at 78.105 64.77)
		(size -2.54 -2.54)
		(stroke
			(width 0)
			(type default)
		)
	)
	(bus_entry
		(at 170.815 114.3)
		(size 1.27 1.27)
		(stroke
			(width 0)
			(type default)
		)
	)
	(bus_entry
		(at 170.815 129.54)
		(size 1.27 1.27)
		(stroke
			(width 0)
			(type default)
		)
	)
	(bus_entry
		(at 78.105 168.91)
		(size -2.54 -2.54)
		(stroke
			(width 0)
			(type default)
		)
	)
	(bus_entry
		(at 170.815 106.68)
		(size 1.27 1.27)
		(stroke
			(width 0)
			(type default)
		)
	)
	(bus_entry
		(at 170.815 172.72)
		(size 1.27 1.27)
		(stroke
			(width 0)
			(type default)
		)
	)
	(bus_entry
		(at 78.105 158.75)
		(size -2.54 -2.54)
		(stroke
			(width 0)
			(type default)
		)
	)
	(bus_entry
		(at 78.105 113.03)
		(size -2.54 -2.54)
		(stroke
			(width 0)
			(type default)
		)
	)
	(bus_entry
		(at 307.34 135.89)
		(size -2.54 -2.54)
		(stroke
			(width 0)
			(type default)
		)
	)
	(bus_entry
		(at 78.105 87.63)
		(size -2.54 -2.54)
		(stroke
			(width 0)
			(type default)
		)
	)
	(bus
		(pts
			(xy 304.8 171.45) (xy 304.8 173.99)
		)
		(stroke
			(width 0)
			(type default)
		)
	)
	(wire
		(pts
			(xy 78.105 184.15) (xy 87.63 184.15)
		)
		(stroke
			(width 0)
			(type default)
		)
	)
	(wire
		(pts
			(xy 131.445 245.745) (xy 128.27 245.745)
		)
		(stroke
			(width 0)
			(type default)
		)
	)
	(wire
		(pts
			(xy 78.105 156.21) (xy 87.63 156.21)
		)
		(stroke
			(width 0)
			(type default)
		)
	)
	(wire
		(pts
			(xy 136.525 245.745) (xy 142.24 245.745)
		)
		(stroke
			(width 0)
			(type default)
		)
	)
	(wire
		(pts
			(xy 307.34 156.21) (xy 317.5 156.21)
		)
		(stroke
			(width 0)
			(type default)
		)
	)
	(bus
		(pts
			(xy 75.565 138.43) (xy 75.565 140.97)
		)
		(stroke
			(width 0)
			(type default)
		)
	)
	(bus
		(pts
			(xy 304.8 97.79) (xy 304.8 100.33)
		)
		(stroke
			(width 0)
			(type default)
		)
	)
	(wire
		(pts
			(xy 186.055 69.85) (xy 218.44 69.85)
		)
		(stroke
			(width 0)
			(type default)
		)
	)
	(bus
		(pts
			(xy 170.18 99.695) (xy 170.815 100.33)
		)
		(stroke
			(width 0)
			(type default)
		)
	)
	(wire
		(pts
			(xy 78.105 163.83) (xy 87.63 163.83)
		)
		(stroke
			(width 0)
			(type default)
		)
	)
	(wire
		(pts
			(xy 172.085 107.95) (xy 218.44 107.95)
		)
		(stroke
			(width 0)
			(type default)
		)
	)
	(wire
		(pts
			(xy 78.105 77.47) (xy 87.63 77.47)
		)
		(stroke
			(width 0)
			(type default)
		)
	)
	(bus
		(pts
			(xy 304.8 128.27) (xy 304.8 130.81)
		)
		(stroke
			(width 0)
			(type default)
		)
	)
	(wire
		(pts
			(xy 307.34 69.85) (xy 317.5 69.85)
		)
		(stroke
			(width 0)
			(type default)
		)
	)
	(wire
		(pts
			(xy 307.34 72.39) (xy 317.5 72.39)
		)
		(stroke
			(width 0)
			(type default)
		)
	)
	(bus
		(pts
			(xy 75.565 100.33) (xy 75.565 102.87)
		)
		(stroke
			(width 0)
			(type default)
		)
	)
	(bus
		(pts
			(xy 75.565 184.15) (xy 75.565 186.69)
		)
		(stroke
			(width 0)
			(type default)
		)
	)
	(wire
		(pts
			(xy 186.055 179.07) (xy 218.44 179.07)
		)
		(stroke
			(width 0)
			(type default)
		)
	)
	(wire
		(pts
			(xy 307.34 87.63) (xy 317.5 87.63)
		)
		(stroke
			(width 0)
			(type default)
		)
	)
	(wire
		(pts
			(xy 317.5 125.73) (xy 307.34 125.73)
		)
		(stroke
			(width 0)
			(type default)
		)
	)
	(bus
		(pts
			(xy 75.565 153.67) (xy 75.565 156.21)
		)
		(stroke
			(width 0)
			(type default)
		)
	)
	(bus
		(pts
			(xy 304.8 62.23) (xy 304.8 64.77)
		)
		(stroke
			(width 0)
			(type default)
		)
	)
	(bus
		(pts
			(xy 304.8 130.81) (xy 304.8 133.35)
		)
		(stroke
			(width 0)
			(type default)
		)
	)
	(bus
		(pts
			(xy 304.8 60.96) (xy 304.8 62.23)
		)
		(stroke
			(width 0)
			(type default)
		)
	)
	(wire
		(pts
			(xy 307.34 135.89) (xy 317.5 135.89)
		)
		(stroke
			(width 0)
			(type default)
		)
	)
	(wire
		(pts
			(xy 172.085 125.73) (xy 218.44 125.73)
		)
		(stroke
			(width 0)
			(type default)
		)
	)
	(bus
		(pts
			(xy 184.785 152.4) (xy 184.785 154.94)
		)
		(stroke
			(width 0)
			(type default)
		)
	)
	(wire
		(pts
			(xy 71.12 238.125) (xy 72.39 238.125)
		)
		(stroke
			(width 0)
			(type default)
		)
	)
	(wire
		(pts
			(xy 140.335 254) (xy 140.335 255.905)
		)
		(stroke
			(width 0)
			(type default)
		)
	)
	(bus
		(pts
			(xy 170.815 104.14) (xy 170.815 106.68)
		)
		(stroke
			(width 0)
			(type default)
		)
	)
	(wire
		(pts
			(xy 72.39 245.745) (xy 79.375 245.745)
		)
		(stroke
			(width 0)
			(type default)
		)
	)
	(wire
		(pts
			(xy 307.34 74.93) (xy 317.5 74.93)
		)
		(stroke
			(width 0)
			(type default)
		)
	)
	(wire
		(pts
			(xy 186.055 85.09) (xy 218.44 85.09)
		)
		(stroke
			(width 0)
			(type default)
		)
	)
	(wire
		(pts
			(xy 78.105 85.09) (xy 87.63 85.09)
		)
		(stroke
			(width 0)
			(type default)
		)
	)
	(bus
		(pts
			(xy 184.785 177.8) (xy 184.785 180.34)
		)
		(stroke
			(width 0)
			(type default)
		)
	)
	(bus
		(pts
			(xy 198.755 149.86) (xy 198.755 185.42)
		)
		(stroke
			(width 0)
			(type default)
		)
	)
	(wire
		(pts
			(xy 216.535 59.69) (xy 218.44 59.69)
		)
		(stroke
			(width 0)
			(type default)
		)
	)
	(wire
		(pts
			(xy 78.105 80.01) (xy 87.63 80.01)
		)
		(stroke
			(width 0)
			(type default)
		)
	)
	(wire
		(pts
			(xy 136.525 254) (xy 140.335 254)
		)
		(stroke
			(width 0)
			(type default)
		)
	)
	(bus
		(pts
			(xy 304.165 60.325) (xy 304.8 60.96)
		)
		(stroke
			(width 0)
			(type default)
		)
	)
	(bus
		(pts
			(xy 75.565 69.85) (xy 75.565 72.39)
		)
		(stroke
			(width 0)
			(type default)
		)
	)
	(bus
		(pts
			(xy 170.815 114.3) (xy 170.815 116.84)
		)
		(stroke
			(width 0)
			(type default)
		)
	)
	(wire
		(pts
			(xy 78.105 153.67) (xy 87.63 153.67)
		)
		(stroke
			(width 0)
			(type default)
		)
	)
	(wire
		(pts
			(xy 78.105 72.39) (xy 87.63 72.39)
		)
		(stroke
			(width 0)
			(type default)
		)
	)
	(bus
		(pts
			(xy 304.8 176.53) (xy 304.8 179.07)
		)
		(stroke
			(width 0)
			(type default)
		)
	)
	(wire
		(pts
			(xy 78.105 146.05) (xy 87.63 146.05)
		)
		(stroke
			(width 0)
			(type default)
		)
	)
	(wire
		(pts
			(xy 307.34 168.91) (xy 317.5 168.91)
		)
		(stroke
			(width 0)
			(type default)
		)
	)
	(wire
		(pts
			(xy 78.105 189.23) (xy 87.63 189.23)
		)
		(stroke
			(width 0)
			(type default)
		)
	)
	(bus
		(pts
			(xy 170.815 157.48) (xy 170.815 162.56)
		)
		(stroke
			(width 0)
			(type default)
		)
	)
	(wire
		(pts
			(xy 186.055 90.17) (xy 218.44 90.17)
		)
		(stroke
			(width 0)
			(type default)
		)
	)
	(bus
		(pts
			(xy 304.8 67.31) (xy 304.8 69.85)
		)
		(stroke
			(width 0)
			(type default)
		)
	)
	(bus
		(pts
			(xy 198.12 55.88) (xy 198.755 56.515)
		)
		(stroke
			(width 0)
			(type default)
		)
	)
	(wire
		(pts
			(xy 172.085 130.81) (xy 218.44 130.81)
		)
		(stroke
			(width 0)
			(type default)
		)
	)
	(bus
		(pts
			(xy 304.8 133.35) (xy 304.8 135.89)
		)
		(stroke
			(width 0)
			(type default)
		)
	)
	(wire
		(pts
			(xy 307.34 166.37) (xy 317.5 166.37)
		)
		(stroke
			(width 0)
			(type default)
		)
	)
	(bus
		(pts
			(xy 170.815 106.68) (xy 170.815 111.76)
		)
		(stroke
			(width 0)
			(type default)
		)
	)
	(bus
		(pts
			(xy 304.8 153.67) (xy 304.8 156.21)
		)
		(stroke
			(width 0)
			(type default)
		)
	)
	(wire
		(pts
			(xy 307.34 107.95) (xy 317.5 107.95)
		)
		(stroke
			(width 0)
			(type default)
		)
	)
	(wire
		(pts
			(xy 78.1174 133.35) (xy 87.63 133.35)
		)
		(stroke
			(width 0)
			(type default)
		)
	)
	(bus
		(pts
			(xy 184.785 180.34) (xy 184.785 182.88)
		)
		(stroke
			(width 0)
			(type default)
		)
	)
	(bus
		(pts
			(xy 304.8 138.43) (xy 304.8 140.97)
		)
		(stroke
			(width 0)
			(type default)
		)
	)
	(bus
		(pts
			(xy 304.8 64.77) (xy 304.8 67.31)
		)
		(stroke
			(width 0)
			(type default)
		)
	)
	(bus
		(pts
			(xy 184.785 68.58) (xy 184.785 71.12)
		)
		(stroke
			(width 0)
			(type default)
		)
	)
	(wire
		(pts
			(xy 78.105 128.27) (xy 87.63 128.27)
		)
		(stroke
			(width 0)
			(type default)
		)
	)
	(bus
		(pts
			(xy 184.785 76.2) (xy 184.785 78.74)
		)
		(stroke
			(width 0)
			(type default)
		)
	)
	(bus
		(pts
			(xy 75.565 168.91) (xy 75.565 171.45)
		)
		(stroke
			(width 0)
			(type default)
		)
	)
	(bus
		(pts
			(xy 184.785 134.62) (xy 184.785 142.24)
		)
		(stroke
			(width 0)
			(type default)
		)
	)
	(wire
		(pts
			(xy 307.34 97.79) (xy 317.5 97.79)
		)
		(stroke
			(width 0)
			(type default)
		)
	)
	(wire
		(pts
			(xy 78.105 105.41) (xy 87.63 105.41)
		)
		(stroke
			(width 0)
			(type default)
		)
	)
	(wire
		(pts
			(xy 307.34 123.19) (xy 317.5 123.19)
		)
		(stroke
			(width 0)
			(type default)
		)
	)
	(bus
		(pts
			(xy 304.8 166.37) (xy 304.8 168.91)
		)
		(stroke
			(width 0)
			(type default)
		)
	)
	(wire
		(pts
			(xy 78.105 166.37) (xy 87.63 166.37)
		)
		(stroke
			(width 0)
			(type default)
		)
	)
	(wire
		(pts
			(xy 307.34 115.57) (xy 317.5 115.57)
		)
		(stroke
			(width 0)
			(type default)
		)
	)
	(wire
		(pts
			(xy 313.055 95.25) (xy 317.5 95.25)
		)
		(stroke
			(width 0)
			(type default)
		)
	)
	(bus
		(pts
			(xy 170.815 172.72) (xy 170.815 175.26)
		)
		(stroke
			(width 0)
			(type default)
		)
	)
	(wire
		(pts
			(xy 172.085 115.57) (xy 218.44 115.57)
		)
		(stroke
			(width 0)
			(type default)
		)
	)
	(bus
		(pts
			(xy 170.815 116.84) (xy 170.815 119.38)
		)
		(stroke
			(width 0)
			(type default)
		)
	)
	(wire
		(pts
			(xy 307.34 133.35) (xy 317.5 133.35)
		)
		(stroke
			(width 0)
			(type default)
		)
	)
	(bus
		(pts
			(xy 184.785 142.24) (xy 184.785 152.4)
		)
		(stroke
			(width 0)
			(type default)
		)
	)
	(wire
		(pts
			(xy 78.105 102.87) (xy 87.63 102.87)
		)
		(stroke
			(width 0)
			(type default)
		)
	)
	(wire
		(pts
			(xy 307.34 82.55) (xy 317.5 82.55)
		)
		(stroke
			(width 0)
			(type default)
		)
	)
	(wire
		(pts
			(xy 317.5 176.53) (xy 307.34 176.53)
		)
		(stroke
			(width 0)
			(type default)
		)
	)
	(bus
		(pts
			(xy 75.565 72.39) (xy 75.565 74.93)
		)
		(stroke
			(width 0)
			(type default)
		)
	)
	(wire
		(pts
			(xy 307.34 184.15) (xy 317.5 184.15)
		)
		(stroke
			(width 0)
			(type default)
		)
	)
	(wire
		(pts
			(xy 186.055 80.01) (xy 218.44 80.01)
		)
		(stroke
			(width 0)
			(type default)
		)
	)
	(wire
		(pts
			(xy 78.105 90.17) (xy 87.63 90.17)
		)
		(stroke
			(width 0)
			(type default)
		)
	)
	(wire
		(pts
			(xy 307.34 138.43) (xy 317.5 138.43)
		)
		(stroke
			(width 0)
			(type default)
		)
	)
	(wire
		(pts
			(xy 307.34 100.33) (xy 317.5 100.33)
		)
		(stroke
			(width 0)
			(type default)
		)
	)
	(wire
		(pts
			(xy 315.595 59.69) (xy 317.5 59.69)
		)
		(stroke
			(width 0)
			(type default)
		)
	)
	(wire
		(pts
			(xy 72.39 245.745) (xy 72.39 248.285)
		)
		(stroke
			(width 0)
			(type default)
		)
	)
	(bus
		(pts
			(xy 168.275 99.695) (xy 170.18 99.695)
		)
		(stroke
			(width 0)
			(type default)
		)
	)
	(wire
		(pts
			(xy 186.055 92.71) (xy 218.44 92.71)
		)
		(stroke
			(width 0)
			(type default)
		)
	)
	(wire
		(pts
			(xy 186.055 184.15) (xy 218.44 184.15)
		)
		(stroke
			(width 0)
			(type default)
		)
	)
	(wire
		(pts
			(xy 172.085 102.87) (xy 218.44 102.87)
		)
		(stroke
			(width 0)
			(type default)
		)
	)
	(wire
		(pts
			(xy 78.105 82.55) (xy 87.63 82.55)
		)
		(stroke
			(width 0)
			(type default)
		)
	)
	(wire
		(pts
			(xy 78.105 173.99) (xy 87.63 173.99)
		)
		(stroke
			(width 0)
			(type default)
		)
	)
	(wire
		(pts
			(xy 62.865 238.125) (xy 66.04 238.125)
		)
		(stroke
			(width 0)
			(type default)
		)
	)
	(bus
		(pts
			(xy 184.15 63.5) (xy 184.785 64.135)
		)
		(stroke
			(width 0)
			(type default)
		)
	)
	(bus
		(pts
			(xy 304.8 77.47) (xy 304.8 80.01)
		)
		(stroke
			(width 0)
			(type default)
		)
	)
	(wire
		(pts
			(xy 307.34 130.81) (xy 317.5 130.81)
		)
		(stroke
			(width 0)
			(type default)
		)
	)
	(bus
		(pts
			(xy 75.565 161.29) (xy 75.565 163.83)
		)
		(stroke
			(width 0)
			(type default)
		)
	)
	(wire
		(pts
			(xy 172.085 158.75) (xy 218.44 158.75)
		)
		(stroke
			(width 0)
			(type default)
		)
	)
	(bus
		(pts
			(xy 304.8 74.93) (xy 304.8 77.47)
		)
		(stroke
			(width 0)
			(type default)
		)
	)
	(wire
		(pts
			(xy 307.34 181.61) (xy 317.5 181.61)
		)
		(stroke
			(width 0)
			(type default)
		)
	)
	(bus
		(pts
			(xy 75.565 173.99) (xy 75.565 176.53)
		)
		(stroke
			(width 0)
			(type default)
		)
	)
	(bus
		(pts
			(xy 184.785 86.36) (xy 184.785 88.9)
		)
		(stroke
			(width 0)
			(type default)
		)
	)
	(wire
		(pts
			(xy 307.34 128.27) (xy 317.5 128.27)
		)
		(stroke
			(width 0)
			(type default)
		)
	)
	(wire
		(pts
			(xy 307.34 85.09) (xy 317.5 85.09)
		)
		(stroke
			(width 0)
			(type default)
		)
	)
	(wire
		(pts
			(xy 186.055 72.39) (xy 218.44 72.39)
		)
		(stroke
			(width 0)
			(type default)
		)
	)
	(wire
		(pts
			(xy 172.085 173.99) (xy 218.44 173.99)
		)
		(stroke
			(width 0)
			(type default)
		)
	)
	(bus
		(pts
			(xy 170.815 119.38) (xy 170.815 121.92)
		)
		(stroke
			(width 0)
			(type default)
		)
	)
	(bus
		(pts
			(xy 304.8 120.65) (xy 304.8 123.19)
		)
		(stroke
			(width 0)
			(type default)
		)
	)
	(wire
		(pts
			(xy 213.995 95.25) (xy 218.44 95.25)
		)
		(stroke
			(width 0)
			(type default)
		)
	)
	(wire
		(pts
			(xy 172.085 148.59) (xy 218.44 148.59)
		)
		(stroke
			(width 0)
			(type default)
		)
	)
	(wire
		(pts
			(xy 78.105 125.73) (xy 78.153 125.73)
		)
		(stroke
			(width 0)
			(type default)
		)
	)
	(wire
		(pts
			(xy 307.34 90.17) (xy 317.5 90.17)
		)
		(stroke
			(width 0)
			(type default)
		)
	)
	(wire
		(pts
			(xy 216.535 58.42) (xy 216.535 59.69)
		)
		(stroke
			(width 0)
			(type default)
		)
	)
	(wire
		(pts
			(xy 78.105 138.43) (xy 87.63 138.43)
		)
		(stroke
			(width 0)
			(type default)
		)
	)
	(wire
		(pts
			(xy 71.12 245.745) (xy 72.39 245.745)
		)
		(stroke
			(width 0)
			(type default)
		)
	)
	(wire
		(pts
			(xy 172.085 176.53) (xy 218.44 176.53)
		)
		(stroke
			(width 0)
			(type default)
		)
	)
	(wire
		(pts
			(xy 307.34 179.07) (xy 317.5 179.07)
		)
		(stroke
			(width 0)
			(type default)
		)
	)
	(bus
		(pts
			(xy 75.565 176.53) (xy 75.565 179.07)
		)
		(stroke
			(width 0)
			(type default)
		)
	)
	(wire
		(pts
			(xy 142.24 245.745) (xy 142.24 243.84)
		)
		(stroke
			(width 0)
			(type default)
		)
	)
	(wire
		(pts
			(xy 78.105 143.51) (xy 87.63 143.51)
		)
		(stroke
			(width 0)
			(type default)
		)
	)
	(bus
		(pts
			(xy 75.565 135.89) (xy 75.565 138.43)
		)
		(stroke
			(width 0)
			(type default)
		)
	)
	(wire
		(pts
			(xy 172.085 138.43) (xy 218.44 138.43)
		)
		(stroke
			(width 0)
			(type default)
		)
	)
	(wire
		(pts
			(xy 78.105 110.49) (xy 87.63 110.49)
		)
		(stroke
			(width 0)
			(type default)
		)
	)
	(bus
		(pts
			(xy 75.565 140.97) (xy 75.565 143.51)
		)
		(stroke
			(width 0)
			(type default)
		)
	)
	(bus
		(pts
			(xy 184.785 73.66) (xy 184.785 76.2)
		)
		(stroke
			(width 0)
			(type default)
		)
	)
	(bus
		(pts
			(xy 75.565 125.73) (xy 75.565 133.35)
		)
		(stroke
			(width 0)
			(type default)
		)
	)
	(wire
		(pts
			(xy 200.025 186.69) (xy 218.44 186.69)
		)
		(stroke
			(width 0)
			(type default)
		)
	)
	(bus
		(pts
			(xy 184.785 154.94) (xy 184.785 177.8)
		)
		(stroke
			(width 0)
			(type default)
		)
	)
	(polyline
		(pts
			(xy 109.855 221.615) (xy 109.855 284.48)
		)
		(stroke
			(width 0)
			(type default)
		)
	)
	(wire
		(pts
			(xy 186.055 87.63) (xy 218.44 87.63)
		)
		(stroke
			(width 0)
			(type default)
		)
	)
	(wire
		(pts
			(xy 307.34 105.41) (xy 317.5 105.41)
		)
		(stroke
			(width 0)
			(type default)
		)
	)
	(bus
		(pts
			(xy 75.565 115.57) (xy 75.565 118.11)
		)
		(stroke
			(width 0)
			(type default)
		)
	)
	(wire
		(pts
			(xy 186.055 133.35) (xy 218.44 133.35)
		)
		(stroke
			(width 0)
			(type default)
		)
	)
	(wire
		(pts
			(xy 213.995 161.29) (xy 218.44 161.29)
		)
		(stroke
			(width 0)
			(type default)
		)
	)
	(wire
		(pts
			(xy 78.105 179.07) (xy 87.63 179.07)
		)
		(stroke
			(width 0)
			(type default)
		)
	)
	(wire
		(pts
			(xy 172.085 120.65) (xy 218.44 120.65)
		)
		(stroke
			(width 0)
			(type default)
		)
	)
	(wire
		(pts
			(xy 307.34 64.77) (xy 317.5 64.77)
		)
		(stroke
			(width 0)
			(type default)
		)
	)
	(wire
		(pts
			(xy 186.055 82.55) (xy 218.44 82.55)
		)
		(stroke
			(width 0)
			(type default)
		)
	)
	(wire
		(pts
			(xy 78.105 130.81) (xy 78.2242 130.81)
		)
		(stroke
			(width 0)
			(type default)
		)
	)
	(bus
		(pts
			(xy 75.565 105.41) (xy 75.565 107.95)
		)
		(stroke
			(width 0)
			(type default)
		)
	)
	(wire
		(pts
			(xy 78.105 67.31) (xy 87.63 67.31)
		)
		(stroke
			(width 0)
			(type default)
		)
	)
	(wire
		(pts
			(xy 186.055 100.33) (xy 218.44 100.33)
		)
		(stroke
			(width 0)
			(type default)
		)
	)
	(bus
		(pts
			(xy 304.8 181.61) (xy 304.8 184.15)
		)
		(stroke
			(width 0)
			(type default)
		)
	)
	(wire
		(pts
			(xy 78.105 120.65) (xy 87.63 120.65)
		)
		(stroke
			(width 0)
			(type default)
		)
	)
	(bus
		(pts
			(xy 304.8 85.09) (xy 304.8 87.63)
		)
		(stroke
			(width 0)
			(type default)
		)
	)
	(wire
		(pts
			(xy 307.34 148.59) (xy 317.5 148.59)
		)
		(stroke
			(width 0)
			(type default)
		)
	)
	(bus
		(pts
			(xy 75.565 181.61) (xy 75.565 184.15)
		)
		(stroke
			(width 0)
			(type default)
		)
	)
	(wire
		(pts
			(xy 172.085 163.83) (xy 218.44 163.83)
		)
		(stroke
			(width 0)
			(type default)
		)
	)
	(wire
		(pts
			(xy 172.085 105.41) (xy 218.44 105.41)
		)
		(stroke
			(width 0)
			(type default)
		)
	)
	(bus
		(pts
			(xy 75.565 118.11) (xy 75.565 120.65)
		)
		(stroke
			(width 0)
			(type default)
		)
	)
	(wire
		(pts
			(xy 307.34 77.47) (xy 317.5 77.47)
		)
		(stroke
			(width 0)
			(type default)
		)
	)
	(wire
		(pts
			(xy 85.725 59.69) (xy 87.63 59.69)
		)
		(stroke
			(width 0)
			(type default)
		)
	)
	(wire
		(pts
			(xy 307.34 102.87) (xy 317.5 102.87)
		)
		(stroke
			(width 0)
			(type default)
		)
	)
	(wire
		(pts
			(xy 78.105 148.59) (xy 87.63 148.59)
		)
		(stroke
			(width 0)
			(type default)
		)
	)
	(wire
		(pts
			(xy 172.085 168.91) (xy 218.44 168.91)
		)
		(stroke
			(width 0)
			(type default)
		)
	)
	(bus
		(pts
			(xy 304.8 100.33) (xy 304.8 102.87)
		)
		(stroke
			(width 0)
			(type default)
		)
	)
	(wire
		(pts
			(xy 128.27 254) (xy 131.445 254)
		)
		(stroke
			(width 0)
			(type default)
		)
	)
	(bus
		(pts
			(xy 304.8 156.21) (xy 304.8 161.29)
		)
		(stroke
			(width 0)
			(type default)
		)
	)
	(wire
		(pts
			(xy 307.34 118.11) (xy 317.5 118.11)
		)
		(stroke
			(width 0)
			(type default)
		)
	)
	(wire
		(pts
			(xy 200.025 151.13) (xy 218.44 151.13)
		)
		(stroke
			(width 0)
			(type default)
		)
	)
	(bus
		(pts
			(xy 74.93 60.325) (xy 75.565 60.96)
		)
		(stroke
			(width 0)
			(type default)
		)
	)
	(bus
		(pts
			(xy 75.565 163.83) (xy 75.565 166.37)
		)
		(stroke
			(width 0)
			(type default)
		)
	)
	(bus
		(pts
			(xy 304.8 161.29) (xy 304.8 163.83)
		)
		(stroke
			(width 0)
			(type default)
		)
	)
	(bus
		(pts
			(xy 75.565 80.01) (xy 75.565 82.55)
		)
		(stroke
			(width 0)
			(type default)
		)
	)
	(bus
		(pts
			(xy 304.8 110.49) (xy 304.8 113.03)
		)
		(stroke
			(width 0)
			(type default)
		)
	)
	(bus
		(pts
			(xy 75.565 148.59) (xy 75.565 151.13)
		)
		(stroke
			(width 0)
			(type default)
		)
	)
	(wire
		(pts
			(xy 186.055 135.89) (xy 218.44 135.89)
		)
		(stroke
			(width 0)
			(type default)
		)
	)
	(wire
		(pts
			(xy 79.375 245.745) (xy 88.265 245.745)
		)
		(stroke
			(width 0)
			(type default)
		)
	)
	(wire
		(pts
			(xy 78.105 168.91) (xy 87.63 168.91)
		)
		(stroke
			(width 0)
			(type default)
		)
	)
	(bus
		(pts
			(xy 75.565 156.21) (xy 75.565 161.29)
		)
		(stroke
			(width 0)
			(type default)
		)
	)
	(wire
		(pts
			(xy 307.34 151.13) (xy 317.5 151.13)
		)
		(stroke
			(width 0)
			(type default)
		)
	)
	(bus
		(pts
			(xy 75.565 179.07) (xy 75.565 181.61)
		)
		(stroke
			(width 0)
			(type default)
		)
	)
	(wire
		(pts
			(xy 313.055 161.29) (xy 317.5 161.29)
		)
		(stroke
			(width 0)
			(type default)
		)
	)
	(bus
		(pts
			(xy 170.815 147.32) (xy 170.815 157.48)
		)
		(stroke
			(width 0)
			(type default)
		)
	)
	(bus
		(pts
			(xy 304.8 80.01) (xy 304.8 82.55)
		)
		(stroke
			(width 0)
			(type default)
		)
	)
	(bus
		(pts
			(xy 73.025 60.325) (xy 74.93 60.325)
		)
		(stroke
			(width 0)
			(type default)
		)
	)
	(bus
		(pts
			(xy 75.565 110.49) (xy 75.565 113.03)
		)
		(stroke
			(width 0)
			(type default)
		)
	)
	(bus
		(pts
			(xy 75.565 120.65) (xy 75.565 125.73)
		)
		(stroke
			(width 0)
			(type default)
		)
	)
	(wire
		(pts
			(xy 78.105 135.89) (xy 87.63 135.89)
		)
		(stroke
			(width 0)
			(type default)
		)
	)
	(wire
		(pts
			(xy 213.995 64.77) (xy 218.44 64.77)
		)
		(stroke
			(width 0)
			(type default)
		)
	)
	(bus
		(pts
			(xy 75.565 85.09) (xy 75.565 87.63)
		)
		(stroke
			(width 0)
			(type default)
		)
	)
	(wire
		(pts
			(xy 307.34 146.05) (xy 317.5 146.05)
		)
		(stroke
			(width 0)
			(type default)
		)
	)
	(bus
		(pts
			(xy 75.565 67.31) (xy 75.565 69.85)
		)
		(stroke
			(width 0)
			(type default)
		)
	)
	(bus
		(pts
			(xy 75.565 74.93) (xy 75.565 77.47)
		)
		(stroke
			(width 0)
			(type default)
		)
	)
	(wire
		(pts
			(xy 79.375 245.745) (xy 79.375 248.285)
		)
		(stroke
			(width 0)
			(type default)
		)
	)
	(bus
		(pts
			(xy 75.565 133.35) (xy 75.565 135.89)
		)
		(stroke
			(width 0)
			(type default)
		)
	)
	(bus
		(pts
			(xy 184.785 66.04) (xy 184.785 68.58)
		)
		(stroke
			(width 0)
			(type default)
		)
	)
	(wire
		(pts
			(xy 82.55 95.25) (xy 87.63 95.25)
		)
		(stroke
			(width 0)
			(type default)
		)
	)
	(bus
		(pts
			(xy 75.565 107.95) (xy 75.565 110.49)
		)
		(stroke
			(width 0)
			(type default)
		)
	)
	(bus
		(pts
			(xy 304.8 82.55) (xy 304.8 85.09)
		)
		(stroke
			(width 0)
			(type default)
		)
	)
	(bus
		(pts
			(xy 75.565 166.37) (xy 75.565 168.91)
		)
		(stroke
			(width 0)
			(type default)
		)
	)
	(wire
		(pts
			(xy 315.595 58.42) (xy 315.595 59.69)
		)
		(stroke
			(width 0)
			(type default)
		)
	)
	(bus
		(pts
			(xy 75.565 82.55) (xy 75.565 85.09)
		)
		(stroke
			(width 0)
			(type default)
		)
	)
	(wire
		(pts
			(xy 78.105 133.35) (xy 78.1174 133.35)
		)
		(stroke
			(width 0)
			(type default)
		)
	)
	(wire
		(pts
			(xy 172.085 113.03) (xy 218.44 113.03)
		)
		(stroke
			(width 0)
			(type default)
		)
	)
	(bus
		(pts
			(xy 182.245 63.5) (xy 184.15 63.5)
		)
		(stroke
			(width 0)
			(type default)
		)
	)
	(wire
		(pts
			(xy 78.2242 130.81) (xy 87.63 130.81)
		)
		(stroke
			(width 0)
			(type default)
		)
	)
	(wire
		(pts
			(xy 307.34 120.65) (xy 317.5 120.65)
		)
		(stroke
			(width 0)
			(type default)
		)
	)
	(wire
		(pts
			(xy 186.055 67.31) (xy 218.44 67.31)
		)
		(stroke
			(width 0)
			(type default)
		)
	)
	(bus
		(pts
			(xy 304.8 72.39) (xy 304.8 74.93)
		)
		(stroke
			(width 0)
			(type default)
		)
	)
	(wire
		(pts
			(xy 186.055 143.51) (xy 218.44 143.51)
		)
		(stroke
			(width 0)
			(type default)
		)
	)
	(wire
		(pts
			(xy 307.34 92.71) (xy 317.5 92.71)
		)
		(stroke
			(width 0)
			(type default)
		)
	)
	(wire
		(pts
			(xy 78.105 113.03) (xy 87.63 113.03)
		)
		(stroke
			(width 0)
			(type default)
		)
	)
	(wire
		(pts
			(xy 186.055 153.67) (xy 218.44 153.67)
		)
		(stroke
			(width 0)
			(type default)
		)
	)
	(wire
		(pts
			(xy 186.055 156.21) (xy 218.44 156.21)
		)
		(stroke
			(width 0)
			(type default)
		)
	)
	(bus
		(pts
			(xy 304.8 107.95) (xy 304.8 110.49)
		)
		(stroke
			(width 0)
			(type default)
		)
	)
	(bus
		(pts
			(xy 304.8 173.99) (xy 304.8 176.53)
		)
		(stroke
			(width 0)
			(type default)
		)
	)
	(wire
		(pts
			(xy 307.34 189.23) (xy 317.5 189.23)
		)
		(stroke
			(width 0)
			(type default)
		)
	)
	(bus
		(pts
			(xy 75.565 64.77) (xy 75.565 67.31)
		)
		(stroke
			(width 0)
			(type default)
		)
	)
	(bus
		(pts
			(xy 184.785 71.12) (xy 184.785 73.66)
		)
		(stroke
			(width 0)
			(type default)
		)
	)
	(wire
		(pts
			(xy 78.105 69.85) (xy 87.63 69.85)
		)
		(stroke
			(width 0)
			(type default)
		)
	)
	(wire
		(pts
			(xy 78.105 115.57) (xy 87.63 115.57)
		)
		(stroke
			(width 0)
			(type default)
		)
	)
	(bus
		(pts
			(xy 170.815 137.16) (xy 170.815 139.7)
		)
		(stroke
			(width 0)
			(type default)
		)
	)
	(bus
		(pts
			(xy 170.815 111.76) (xy 170.815 114.3)
		)
		(stroke
			(width 0)
			(type default)
		)
	)
	(bus
		(pts
			(xy 75.565 97.79) (xy 75.565 100.33)
		)
		(stroke
			(width 0)
			(type default)
		)
	)
	(bus
		(pts
			(xy 304.8 123.19) (xy 304.8 125.73)
		)
		(stroke
			(width 0)
			(type default)
		)
	)
	(bus
		(pts
			(xy 304.8 151.13) (xy 304.8 153.67)
		)
		(stroke
			(width 0)
			(type default)
		)
	)
	(wire
		(pts
			(xy 34.29 245.745) (xy 66.04 245.745)
		)
		(stroke
			(width 0)
			(type default)
		)
	)
	(wire
		(pts
			(xy 34.29 245.745) (xy 34.29 248.285)
		)
		(stroke
			(width 0)
			(type default)
		)
	)
	(wire
		(pts
			(xy 78.153 125.73) (xy 87.63 125.73)
		)
		(stroke
			(width 0)
			(type default)
		)
	)
	(wire
		(pts
			(xy 78.105 74.93) (xy 87.63 74.93)
		)
		(stroke
			(width 0)
			(type default)
		)
	)
	(wire
		(pts
			(xy 186.055 97.79) (xy 218.44 97.79)
		)
		(stroke
			(width 0)
			(type default)
		)
	)
	(bus
		(pts
			(xy 302.26 60.325) (xy 304.165 60.325)
		)
		(stroke
			(width 0)
			(type default)
		)
	)
	(bus
		(pts
			(xy 75.565 146.05) (xy 75.565 148.59)
		)
		(stroke
			(width 0)
			(type default)
		)
	)
	(bus
		(pts
			(xy 184.785 83.82) (xy 184.785 86.36)
		)
		(stroke
			(width 0)
			(type default)
		)
	)
	(wire
		(pts
			(xy 85.725 58.42) (xy 85.725 59.69)
		)
		(stroke
			(width 0)
			(type default)
		)
	)
	(bus
		(pts
			(xy 184.785 91.44) (xy 184.785 96.52)
		)
		(stroke
			(width 0)
			(type default)
		)
	)
	(wire
		(pts
			(xy 307.34 140.97) (xy 317.5 140.97)
		)
		(stroke
			(width 0)
			(type default)
		)
	)
	(bus
		(pts
			(xy 170.815 121.92) (xy 170.815 124.46)
		)
		(stroke
			(width 0)
			(type default)
		)
	)
	(bus
		(pts
			(xy 75.565 113.03) (xy 75.565 115.57)
		)
		(stroke
			(width 0)
			(type default)
		)
	)
	(bus
		(pts
			(xy 170.815 144.78) (xy 170.815 147.32)
		)
		(stroke
			(width 0)
			(type default)
		)
	)
	(wire
		(pts
			(xy 82.55 161.29) (xy 87.63 161.29)
		)
		(stroke
			(width 0)
			(type default)
		)
	)
	(wire
		(pts
			(xy 78.105 123.19) (xy 87.63 123.19)
		)
		(stroke
			(width 0)
			(type default)
		)
	)
	(bus
		(pts
			(xy 75.565 87.63) (xy 75.565 90.17)
		)
		(stroke
			(width 0)
			(type default)
		)
	)
	(bus
		(pts
			(xy 304.8 118.11) (xy 304.8 120.65)
		)
		(stroke
			(width 0)
			(type default)
		)
	)
	(bus
		(pts
			(xy 304.8 143.51) (xy 304.8 146.05)
		)
		(stroke
			(width 0)
			(type default)
		)
	)
	(bus
		(pts
			(xy 304.8 102.87) (xy 304.8 105.41)
		)
		(stroke
			(width 0)
			(type default)
		)
	)
	(wire
		(pts
			(xy 186.055 74.93) (xy 218.44 74.93)
		)
		(stroke
			(width 0)
			(type default)
		)
	)
	(bus
		(pts
			(xy 196.215 55.88) (xy 198.12 55.88)
		)
		(stroke
			(width 0)
			(type default)
		)
	)
	(wire
		(pts
			(xy 78.105 151.13) (xy 87.63 151.13)
		)
		(stroke
			(width 0)
			(type default)
		)
	)
	(wire
		(pts
			(xy 78.105 158.75) (xy 87.63 158.75)
		)
		(stroke
			(width 0)
			(type default)
		)
	)
	(bus
		(pts
			(xy 75.565 143.51) (xy 75.565 146.05)
		)
		(stroke
			(width 0)
			(type default)
		)
	)
	(wire
		(pts
			(xy 307.34 153.67) (xy 317.5 153.67)
		)
		(stroke
			(width 0)
			(type default)
		)
	)
	(wire
		(pts
			(xy 78.105 171.45) (xy 87.63 171.45)
		)
		(stroke
			(width 0)
			(type default)
		)
	)
	(bus
		(pts
			(xy 304.8 140.97) (xy 304.8 143.51)
		)
		(stroke
			(width 0)
			(type default)
		)
	)
	(bus
		(pts
			(xy 304.8 125.73) (xy 304.8 128.27)
		)
		(stroke
			(width 0)
			(type default)
		)
	)
	(bus
		(pts
			(xy 304.8 105.41) (xy 304.8 107.95)
		)
		(stroke
			(width 0)
			(type default)
		)
	)
	(wire
		(pts
			(xy 307.34 158.75) (xy 317.5 158.75)
		)
		(stroke
			(width 0)
			(type default)
		)
	)
	(wire
		(pts
			(xy 78.105 87.63) (xy 87.63 87.63)
		)
		(stroke
			(width 0)
			(type default)
		)
	)
	(wire
		(pts
			(xy 78.105 176.53) (xy 87.63 176.53)
		)
		(stroke
			(width 0)
			(type default)
		)
	)
	(bus
		(pts
			(xy 304.8 90.17) (xy 304.8 95.25)
		)
		(stroke
			(width 0)
			(type default)
		)
	)
	(wire
		(pts
			(xy 78.105 92.71) (xy 87.63 92.71)
		)
		(stroke
			(width 0)
			(type default)
		)
	)
	(wire
		(pts
			(xy 78.105 140.97) (xy 87.63 140.97)
		)
		(stroke
			(width 0)
			(type default)
		)
	)
	(wire
		(pts
			(xy 307.34 173.99) (xy 317.5 173.99)
		)
		(stroke
			(width 0)
			(type default)
		)
	)
	(bus
		(pts
			(xy 198.755 56.515) (xy 198.755 149.86)
		)
		(stroke
			(width 0)
			(type default)
		)
	)
	(wire
		(pts
			(xy 307.34 171.45) (xy 317.5 171.45)
		)
		(stroke
			(width 0)
			(type default)
		)
	)
	(wire
		(pts
			(xy 172.085 140.97) (xy 218.44 140.97)
		)
		(stroke
			(width 0)
			(type default)
		)
	)
	(bus
		(pts
			(xy 304.8 146.05) (xy 304.8 148.59)
		)
		(stroke
			(width 0)
			(type default)
		)
	)
	(wire
		(pts
			(xy 78.105 181.61) (xy 87.63 181.61)
		)
		(stroke
			(width 0)
			(type default)
		)
	)
	(wire
		(pts
			(xy 78.105 97.79) (xy 87.63 97.79)
		)
		(stroke
			(width 0)
			(type default)
		)
	)
	(bus
		(pts
			(xy 75.565 171.45) (xy 75.565 173.99)
		)
		(stroke
			(width 0)
			(type default)
		)
	)
	(wire
		(pts
			(xy 186.055 77.47) (xy 218.44 77.47)
		)
		(stroke
			(width 0)
			(type default)
		)
	)
	(wire
		(pts
			(xy 78.105 118.11) (xy 87.63 118.11)
		)
		(stroke
			(width 0)
			(type default)
		)
	)
	(bus
		(pts
			(xy 304.8 184.15) (xy 304.8 186.69)
		)
		(stroke
			(width 0)
			(type default)
		)
	)
	(bus
		(pts
			(xy 170.815 100.33) (xy 170.815 101.6)
		)
		(stroke
			(width 0)
			(type default)
		)
	)
	(bus
		(pts
			(xy 170.815 124.46) (xy 170.815 127)
		)
		(stroke
			(width 0)
			(type default)
		)
	)
	(bus
		(pts
			(xy 184.785 96.52) (xy 184.785 99.06)
		)
		(stroke
			(width 0)
			(type default)
		)
	)
	(bus
		(pts
			(xy 170.815 101.6) (xy 170.815 104.14)
		)
		(stroke
			(width 0)
			(type default)
		)
	)
	(wire
		(pts
			(xy 72.39 238.125) (xy 72.39 245.745)
		)
		(stroke
			(width 0)
			(type default)
		)
	)
	(wire
		(pts
			(xy 34.29 236.855) (xy 34.29 238.125)
		)
		(stroke
			(width 0)
			(type default)
		)
	)
	(bus
		(pts
			(xy 170.815 167.64) (xy 170.815 170.18)
		)
		(stroke
			(width 0)
			(type default)
		)
	)
	(bus
		(pts
			(xy 170.815 127) (xy 170.815 129.54)
		)
		(stroke
			(width 0)
			(type default)
		)
	)
	(wire
		(pts
			(xy 172.085 146.05) (xy 218.44 146.05)
		)
		(stroke
			(width 0)
			(type default)
		)
	)
	(bus
		(pts
			(xy 75.565 102.87) (xy 75.565 105.41)
		)
		(stroke
			(width 0)
			(type default)
		)
	)
	(wire
		(pts
			(xy 78.105 64.77) (xy 87.63 64.77)
		)
		(stroke
			(width 0)
			(type default)
		)
	)
	(bus
		(pts
			(xy 75.565 77.47) (xy 75.565 80.01)
		)
		(stroke
			(width 0)
			(type default)
		)
	)
	(bus
		(pts
			(xy 184.785 81.28) (xy 184.785 83.82)
		)
		(stroke
			(width 0)
			(type default)
		)
	)
	(wire
		(pts
			(xy 307.34 67.31) (xy 317.5 67.31)
		)
		(stroke
			(width 0)
			(type default)
		)
	)
	(wire
		(pts
			(xy 307.34 113.03) (xy 317.5 113.03)
		)
		(stroke
			(width 0)
			(type default)
		)
	)
	(wire
		(pts
			(xy 78.105 100.33) (xy 87.63 100.33)
		)
		(stroke
			(width 0)
			(type default)
		)
	)
	(bus
		(pts
			(xy 304.8 179.07) (xy 304.8 181.61)
		)
		(stroke
			(width 0)
			(type default)
		)
	)
	(bus
		(pts
			(xy 184.785 132.08) (xy 184.785 134.62)
		)
		(stroke
			(width 0)
			(type default)
		)
	)
	(bus
		(pts
			(xy 75.565 62.23) (xy 75.565 64.77)
		)
		(stroke
			(width 0)
			(type default)
		)
	)
	(bus
		(pts
			(xy 304.8 87.63) (xy 304.8 90.17)
		)
		(stroke
			(width 0)
			(type default)
		)
	)
	(bus
		(pts
			(xy 170.815 129.54) (xy 170.815 137.16)
		)
		(stroke
			(width 0)
			(type default)
		)
	)
	(wire
		(pts
			(xy 78.105 107.95) (xy 87.63 107.95)
		)
		(stroke
			(width 0)
			(type default)
		)
	)
	(wire
		(pts
			(xy 307.34 143.51) (xy 317.5 143.51)
		)
		(stroke
			(width 0)
			(type default)
		)
	)
	(bus
		(pts
			(xy 184.785 88.9) (xy 184.785 91.44)
		)
		(stroke
			(width 0)
			(type default)
		)
	)
	(wire
		(pts
			(xy 213.995 189.23) (xy 218.44 189.23)
		)
		(stroke
			(width 0)
			(type default)
		)
	)
	(wire
		(pts
			(xy 307.34 186.69) (xy 317.5 186.69)
		)
		(stroke
			(width 0)
			(type default)
		)
	)
	(bus
		(pts
			(xy 304.8 163.83) (xy 304.8 166.37)
		)
		(stroke
			(width 0)
			(type default)
		)
	)
	(bus
		(pts
			(xy 75.565 95.25) (xy 75.565 97.79)
		)
		(stroke
			(width 0)
			(type default)
		)
	)
	(bus
		(pts
			(xy 170.815 139.7) (xy 170.815 144.78)
		)
		(stroke
			(width 0)
			(type default)
		)
	)
	(bus
		(pts
			(xy 304.8 95.25) (xy 304.8 97.79)
		)
		(stroke
			(width 0)
			(type default)
		)
	)
	(wire
		(pts
			(xy 307.34 163.83) (xy 317.5 163.83)
		)
		(stroke
			(width 0)
			(type default)
		)
	)
	(wire
		(pts
			(xy 34.29 243.205) (xy 34.29 245.745)
		)
		(stroke
			(width 0)
			(type default)
		)
	)
	(bus
		(pts
			(xy 170.815 170.18) (xy 170.815 172.72)
		)
		(stroke
			(width 0)
			(type default)
		)
	)
	(wire
		(pts
			(xy 307.34 80.01) (xy 317.5 80.01)
		)
		(stroke
			(width 0)
			(type default)
		)
	)
	(bus
		(pts
			(xy 304.8 69.85) (xy 304.8 72.39)
		)
		(stroke
			(width 0)
			(type default)
		)
	)
	(bus
		(pts
			(xy 184.785 78.74) (xy 184.785 81.28)
		)
		(stroke
			(width 0)
			(type default)
		)
	)
	(wire
		(pts
			(xy 172.085 171.45) (xy 218.44 171.45)
		)
		(stroke
			(width 0)
			(type default)
		)
	)
	(wire
		(pts
			(xy 78.105 186.69) (xy 87.63 186.69)
		)
		(stroke
			(width 0)
			(type default)
		)
	)
	(bus
		(pts
			(xy 184.785 64.135) (xy 184.785 66.04)
		)
		(stroke
			(width 0)
			(type default)
		)
	)
	(wire
		(pts
			(xy 186.055 181.61) (xy 218.44 181.61)
		)
		(stroke
			(width 0)
			(type default)
		)
	)
	(bus
		(pts
			(xy 304.8 113.03) (xy 304.8 115.57)
		)
		(stroke
			(width 0)
			(type default)
		)
	)
	(bus
		(pts
			(xy 75.565 90.17) (xy 75.565 95.25)
		)
		(stroke
			(width 0)
			(type default)
		)
	)
	(bus
		(pts
			(xy 184.785 99.06) (xy 184.785 132.08)
		)
		(stroke
			(width 0)
			(type default)
		)
	)
	(bus
		(pts
			(xy 304.8 135.89) (xy 304.8 138.43)
		)
		(stroke
			(width 0)
			(type default)
		)
	)
	(wire
		(pts
			(xy 172.085 128.27) (xy 218.44 128.27)
		)
		(stroke
			(width 0)
			(type default)
		)
	)
	(bus
		(pts
			(xy 170.815 162.56) (xy 170.815 167.64)
		)
		(stroke
			(width 0)
			(type default)
		)
	)
	(polyline
		(pts
			(xy 12.7 221.615) (xy 407.67 221.615)
		)
		(stroke
			(width 0)
			(type default)
		)
	)
	(bus
		(pts
			(xy 304.8 115.57) (xy 304.8 118.11)
		)
		(stroke
			(width 0)
			(type default)
		)
	)
	(bus
		(pts
			(xy 304.8 148.59) (xy 304.8 151.13)
		)
		(stroke
			(width 0)
			(type default)
		)
	)
	(bus
		(pts
			(xy 75.565 60.96) (xy 75.565 62.23)
		)
		(stroke
			(width 0)
			(type default)
		)
	)
	(wire
		(pts
			(xy 172.085 118.11) (xy 218.44 118.11)
		)
		(stroke
			(width 0)
			(type default)
		)
	)
	(bus
		(pts
			(xy 75.565 151.13) (xy 75.565 153.67)
		)
		(stroke
			(width 0)
			(type default)
		)
	)
	(bus
		(pts
			(xy 304.8 168.91) (xy 304.8 171.45)
		)
		(stroke
			(width 0)
			(type default)
		)
	)
	(wire
		(pts
			(xy 307.34 110.49) (xy 317.5 110.49)
		)
		(stroke
			(width 0)
			(type default)
		)
	)
	(wire
		(pts
			(xy 172.085 123.19) (xy 218.44 123.19)
		)
		(stroke
			(width 0)
			(type default)
		)
	)
	(label "B.DQS4_P"
		(at 186.055 97.79 0)
		(effects
			(font
				(size 1.27 1.27)
			)
			(justify left bottom)
		)
	)
	(label "A.DQ18"
		(at 78.105 123.19 0)
		(effects
			(font
				(size 1.27 1.27)
			)
			(justify left bottom)
		)
	)
	(label "B.DQ7"
		(at 307.34 163.83 0)
		(effects
			(font
				(size 1.27 1.27)
			)
			(justify left bottom)
		)
	)
	(label "A.CA1"
		(at 172.085 140.97 0)
		(effects
			(font
				(size 1.27 1.27)
			)
			(justify left bottom)
		)
	)
	(label "B.DQ10"
		(at 307.34 151.13 0)
		(effects
			(font
				(size 1.27 1.27)
			)
			(justify left bottom)
		)
	)
	(label "B.DQ26"
		(at 307.34 92.71 0)
		(effects
			(font
				(size 1.27 1.27)
			)
			(justify left bottom)
		)
	)
	(label "B.CA5"
		(at 186.055 87.63 0)
		(effects
			(font
				(size 1.27 1.27)
			)
			(justify left bottom)
		)
	)
	(label "A.DQ31"
		(at 78.105 72.39 0)
		(effects
			(font
				(size 1.27 1.27)
			)
			(justify left bottom)
		)
	)
	(label "A.DQS0_N"
		(at 78.105 171.45 0)
		(effects
			(font
				(size 1.27 1.27)
			)
			(justify left bottom)
		)
	)
	(label "VRN"
		(at 128.27 245.745 180)
		(effects
			(font
				(size 1.27 1.27)
			)
			(justify right bottom)
		)
	)
	(label "A.DQS4_N"
		(at 172.085 176.53 0)
		(effects
			(font
				(size 1.27 1.27)
			)
			(justify left bottom)
		)
	)
	(label "A.CA11"
		(at 172.085 113.03 0)
		(effects
			(font
				(size 1.27 1.27)
			)
			(justify left bottom)
		)
	)
	(label "B.DQS1_P"
		(at 307.34 138.43 0)
		(effects
			(font
				(size 1.27 1.27)
			)
			(justify left bottom)
		)
	)
	(label "B.DQ30"
		(at 307.34 90.17 0)
		(effects
			(font
				(size 1.27 1.27)
			)
			(justify left bottom)
		)
	)
	(label "A.DQS1_P"
		(at 78.105 138.43 0)
		(effects
			(font
				(size 1.27 1.27)
			)
			(justify left bottom)
		)
	)
	(label "A.~{CS1}"
		(at 172.085 138.43 0)
		(effects
			(font
				(size 1.27 1.27)
			)
			(justify left bottom)
		)
	)
	(label "B.DQS4_N"
		(at 186.055 100.33 0)
		(effects
			(font
				(size 1.27 1.27)
			)
			(justify left bottom)
		)
	)
	(label "A.DQ22"
		(at 78.105 113.03 0)
		(effects
			(font
				(size 1.27 1.27)
			)
			(justify left bottom)
		)
	)
	(label "A.DQ27"
		(at 78.105 67.31 0)
		(effects
			(font
				(size 1.27 1.27)
			)
			(justify left bottom)
		)
	)
	(label "B.DQS2_P"
		(at 307.34 107.95 0)
		(effects
			(font
				(size 1.27 1.27)
			)
			(justify left bottom)
		)
	)
	(label "B.DQ27"
		(at 307.34 82.55 0)
		(effects
			(font
				(size 1.27 1.27)
			)
			(justify left bottom)
		)
	)
	(label "B.DQ14"
		(at 307.34 130.81 0)
		(effects
			(font
				(size 1.27 1.27)
			)
			(justify left bottom)
		)
	)
	(label "B.CK1_P"
		(at 186.055 179.07 0)
		(effects
			(font
				(size 1.27 1.27)
			)
			(justify left bottom)
		)
	)
	(label "B.CA2"
		(at 186.055 72.39 0)
		(effects
			(font
				(size 1.27 1.27)
			)
			(justify left bottom)
		)
	)
	(label "A.DQ10"
		(at 78.105 153.67 0)
		(effects
			(font
				(size 1.27 1.27)
			)
			(justify left bottom)
		)
	)
	(label "B.DQ21"
		(at 307.34 100.33 0)
		(effects
			(font
				(size 1.27 1.27)
			)
			(justify left bottom)
		)
	)
	(label "B.DQ1"
		(at 307.34 158.75 0)
		(effects
			(font
				(size 1.27 1.27)
			)
			(justify left bottom)
		)
	)
	(label "A.CA10"
		(at 172.085 115.57 0)
		(effects
			(font
				(size 1.27 1.27)
			)
			(justify left bottom)
		)
	)
	(label "A.CA0"
		(at 172.085 158.75 0)
		(effects
			(font
				(size 1.27 1.27)
			)
			(justify left bottom)
		)
	)
	(label "A.DQ4"
		(at 78.105 173.99 0)
		(effects
			(font
				(size 1.27 1.27)
			)
			(justify left bottom)
		)
	)
	(label "B.DQ23"
		(at 307.34 102.87 0)
		(effects
			(font
				(size 1.27 1.27)
			)
			(justify left bottom)
		)
	)
	(label "A.DQS2_N"
		(at 78.105 110.49 0)
		(effects
			(font
				(size 1.27 1.27)
			)
			(justify left bottom)
		)
	)
	(label "A.CB3"
		(at 78.105 64.77 0)
		(effects
			(font
				(size 1.27 1.27)
			)
			(justify left bottom)
		)
	)
	(label "A.CK0_P"
		(at 172.085 128.27 0)
		(effects
			(font
				(size 1.27 1.27)
			)
			(justify left bottom)
		)
	)
	(label "A.CA4"
		(at 172.085 123.19 0)
		(effects
			(font
				(size 1.27 1.27)
			)
			(justify left bottom)
		)
	)
	(label "A.DQ2"
		(at 78.105 166.37 0)
		(effects
			(font
				(size 1.27 1.27)
			)
			(justify left bottom)
		)
	)
	(label "A.CA9"
		(at 172.085 102.87 0)
		(effects
			(font
				(size 1.27 1.27)
			)
			(justify left bottom)
		)
	)
	(label "A.DQ5"
		(at 78.105 176.53 0)
		(effects
			(font
				(size 1.27 1.27)
			)
			(justify left bottom)
		)
	)
	(label "VRP"
		(at 128.27 254 180)
		(effects
			(font
				(size 1.27 1.27)
			)
			(justify right bottom)
		)
	)
	(label "B.DQ12"
		(at 307.34 135.89 0)
		(effects
			(font
				(size 1.27 1.27)
			)
			(justify left bottom)
		)
	)
	(label "B.DQ3"
		(at 307.34 179.07 0)
		(effects
			(font
				(size 1.27 1.27)
			)
			(justify left bottom)
		)
	)
	(label "A.DQ12"
		(at 78.105 128.27 0)
		(effects
			(font
				(size 1.27 1.27)
			)
			(justify left bottom)
		)
	)
	(label "A.CA5"
		(at 172.085 118.11 0)
		(effects
			(font
				(size 1.27 1.27)
			)
			(justify left bottom)
		)
	)
	(label "B.CA4"
		(at 186.055 90.17 0)
		(effects
			(font
				(size 1.27 1.27)
			)
			(justify left bottom)
		)
	)
	(label "A.DQ25"
		(at 78.105 92.71 0)
		(effects
			(font
				(size 1.27 1.27)
			)
			(justify left bottom)
		)
	)
	(label "A.DQ23"
		(at 78.105 115.57 0)
		(effects
			(font
				(size 1.27 1.27)
			)
			(justify left bottom)
		)
	)
	(label "VRP"
		(at 213.995 189.23 0)
		(effects
			(font
				(size 1.27 1.27)
			)
			(justify left bottom)
		)
	)
	(label "B.DQ29"
		(at 307.34 69.85 0)
		(effects
			(font
				(size 1.27 1.27)
			)
			(justify left bottom)
		)
	)
	(label "A.DQ28"
		(at 78.105 82.55 0)
		(effects
			(font
				(size 1.27 1.27)
			)
			(justify left bottom)
		)
	)
	(label "B.DQS1_N"
		(at 307.34 140.97 0)
		(effects
			(font
				(size 1.27 1.27)
			)
			(justify left bottom)
		)
	)
	(label "B.CB1"
		(at 307.34 64.77 0)
		(effects
			(font
				(size 1.27 1.27)
			)
			(justify left bottom)
		)
	)
	(label "B.CB3"
		(at 307.34 189.23 0)
		(effects
			(font
				(size 1.27 1.27)
			)
			(justify left bottom)
		)
	)
	(label "A.CB1"
		(at 78.105 156.21 0)
		(effects
			(font
				(size 1.27 1.27)
			)
			(justify left bottom)
		)
	)
	(label "B.DQ2"
		(at 307.34 184.15 0)
		(effects
			(font
				(size 1.27 1.27)
			)
			(justify left bottom)
		)
	)
	(label "A.DQ24"
		(at 78.105 90.17 0)
		(effects
			(font
				(size 1.27 1.27)
			)
			(justify left bottom)
		)
	)
	(label "B.CK0_N"
		(at 186.055 135.89 0)
		(effects
			(font
				(size 1.27 1.27)
			)
			(justify left bottom)
		)
	)
	(label "A.DQS3_P"
		(at 78.105 77.47 0)
		(effects
			(font
				(size 1.27 1.27)
			)
			(justify left bottom)
		)
	)
	(label "A.DQ20"
		(at 78.105 105.41 0)
		(effects
			(font
				(size 1.27 1.27)
			)
			(justify left bottom)
		)
	)
	(label "B.CK0_P"
		(at 186.055 133.35 0)
		(effects
			(font
				(size 1.27 1.27)
			)
			(justify left bottom)
		)
	)
	(label "B.~{DM2}"
		(at 307.34 115.57 0)
		(effects
			(font
				(size 1.27 1.27)
			)
			(justify left bottom)
		)
	)
	(label "B.CA7"
		(at 186.055 143.51 0)
		(effects
			(font
				(size 1.27 1.27)
			)
			(justify left bottom)
		)
	)
	(label "A.DQ26"
		(at 78.105 87.63 0)
		(effects
			(font
				(size 1.27 1.27)
			)
			(justify left bottom)
		)
	)
	(label "A.CA3"
		(at 172.085 148.59 0)
		(effects
			(font
				(size 1.27 1.27)
			)
			(justify left bottom)
		)
	)
	(label "B.CA1"
		(at 186.055 85.09 0)
		(effects
			(font
				(size 1.27 1.27)
			)
			(justify left bottom)
		)
	)
	(label "B.DQ28"
		(at 307.34 67.31 0)
		(effects
			(font
				(size 1.27 1.27)
			)
			(justify left bottom)
		)
	)
	(label "B.DQ19"
		(at 307.34 120.65 0)
		(effects
			(font
				(size 1.27 1.27)
			)
			(justify left bottom)
		)
	)
	(label "A.CA12"
		(at 172.085 105.41 0)
		(effects
			(font
				(size 1.27 1.27)
			)
			(justify left bottom)
		)
	)
	(label "A.DQS4_P"
		(at 172.085 173.99 0)
		(effects
			(font
				(size 1.27 1.27)
			)
			(justify left bottom)
		)
	)
	(label "A.CA8"
		(at 172.085 107.95 0)
		(effects
			(font
				(size 1.27 1.27)
			)
			(justify left bottom)
		)
	)
	(label "A.DQ7"
		(at 78.105 186.69 0)
		(effects
			(font
				(size 1.27 1.27)
			)
			(justify left bottom)
		)
	)
	(label "A.DQ14"
		(at 78.105 135.89 0)
		(effects
			(font
				(size 1.27 1.27)
			)
			(justify left bottom)
		)
	)
	(label "A.DQS2_P"
		(at 78.105 107.95 0)
		(effects
			(font
				(size 1.27 1.27)
			)
			(justify left bottom)
		)
	)
	(label "VREF"
		(at 82.55 161.29 0)
		(effects
			(font
				(size 1.27 1.27)
			)
			(justify left bottom)
		)
	)
	(label "A.DQ6"
		(at 78.105 158.75 0)
		(effects
			(font
				(size 1.27 1.27)
			)
			(justify left bottom)
		)
	)
	(label "B.CA0"
		(at 186.055 74.93 0)
		(effects
			(font
				(size 1.27 1.27)
			)
			(justify left bottom)
		)
	)
	(label "A.CK0_N"
		(at 172.085 130.81 0)
		(effects
			(font
				(size 1.27 1.27)
			)
			(justify left bottom)
		)
	)
	(label "B.CA10"
		(at 186.055 67.31 0)
		(effects
			(font
				(size 1.27 1.27)
			)
			(justify left bottom)
		)
	)
	(label "A.CK1_N"
		(at 172.085 171.45 0)
		(effects
			(font
				(size 1.27 1.27)
			)
			(justify left bottom)
		)
	)
	(label "B.DQ9"
		(at 307.34 148.59 0)
		(effects
			(font
				(size 1.27 1.27)
			)
			(justify left bottom)
		)
	)
	(label "A.DQS3_N"
		(at 78.105 80.01 0)
		(effects
			(font
				(size 1.27 1.27)
			)
			(justify left bottom)
		)
	)
	(label "B.DQ4"
		(at 307.34 186.69 0)
		(effects
			(font
				(size 1.27 1.27)
			)
			(justify left bottom)
		)
	)
	(label "B.DQ24"
		(at 307.34 72.39 0)
		(effects
			(font
				(size 1.27 1.27)
			)
			(justify left bottom)
		)
	)
	(label "B.DQ17"
		(at 307.34 125.73 0)
		(effects
			(font
				(size 1.27 1.27)
			)
			(justify left bottom)
		)
	)
	(label "B.CA8"
		(at 186.055 153.67 0)
		(effects
			(font
				(size 1.27 1.27)
			)
			(justify left bottom)
		)
	)
	(label "B.CA3"
		(at 186.055 92.71 0)
		(effects
			(font
				(size 1.27 1.27)
			)
			(justify left bottom)
		)
	)
	(label "B.DQ5"
		(at 307.34 176.53 0)
		(effects
			(font
				(size 1.27 1.27)
			)
			(justify left bottom)
		)
	)
	(label "B.DQS3_P"
		(at 307.34 77.47 0)
		(effects
			(font
				(size 1.27 1.27)
			)
			(justify left bottom)
		)
	)
	(label "B.CA6"
		(at 186.055 80.01 0)
		(effects
			(font
				(size 1.27 1.27)
			)
			(justify left bottom)
		)
	)
	(label "B.DQ6"
		(at 307.34 166.37 0)
		(effects
			(font
				(size 1.27 1.27)
			)
			(justify left bottom)
		)
	)
	(label "A.DQ19"
		(at 78.105 125.73 0)
		(effects
			(font
				(size 1.27 1.27)
			)
			(justify left bottom)
		)
	)
	(label "A.DQ8"
		(at 78.105 143.51 0)
		(effects
			(font
				(size 1.27 1.27)
			)
			(justify left bottom)
		)
	)
	(label "A.DQ16"
		(at 78.105 120.65 0)
		(effects
			(font
				(size 1.27 1.27)
			)
			(justify left bottom)
		)
	)
	(label "B.DQ20"
		(at 307.34 113.03 0)
		(effects
			(font
				(size 1.27 1.27)
			)
			(justify left bottom)
		)
	)
	(label "A.DQS1_N"
		(at 78.105 140.97 0)
		(effects
			(font
				(size 1.27 1.27)
			)
			(justify left bottom)
		)
	)
	(label "B.CB2"
		(at 307.34 123.19 0)
		(effects
			(font
				(size 1.27 1.27)
			)
			(justify left bottom)
		)
	)
	(label "A.DQ13"
		(at 78.105 151.13 0)
		(effects
			(font
				(size 1.27 1.27)
			)
			(justify left bottom)
		)
	)
	(label "VREF"
		(at 88.265 245.745 0)
		(effects
			(font
				(size 1.27 1.27)
			)
			(justify left bottom)
		)
	)
	(label "A.DQ9"
		(at 78.105 133.35 0)
		(effects
			(font
				(size 1.27 1.27)
			)
			(justify left bottom)
		)
	)
	(label "VRN"
		(at 213.995 64.77 0)
		(effects
			(font
				(size 1.27 1.27)
			)
			(justify left bottom)
		)
	)
	(label "B.DQS2_N"
		(at 307.34 110.49 0)
		(effects
			(font
				(size 1.27 1.27)
			)
			(justify left bottom)
		)
	)
	(label "B.~{CS0}"
		(at 186.055 82.55 0)
		(effects
			(font
				(size 1.27 1.27)
			)
			(justify left bottom)
		)
	)
	(label "A.DQ15"
		(at 78.105 130.81 0)
		(effects
			(font
				(size 1.27 1.27)
			)
			(justify left bottom)
		)
	)
	(label "B.DQS3_N"
		(at 307.34 80.01 0)
		(effects
			(font
				(size 1.27 1.27)
			)
			(justify left bottom)
		)
	)
	(label "B.DQ0"
		(at 307.34 181.61 0)
		(effects
			(font
				(size 1.27 1.27)
			)
			(justify left bottom)
		)
	)
	(label "Control.~{ALERT}"
		(at 200.025 151.13 0)
		(effects
			(font
				(size 1.27 1.27)
			)
			(justify left bottom)
		)
	)
	(label "B.DQ11"
		(at 307.34 146.05 0)
		(effects
			(font
				(size 1.27 1.27)
			)
			(justify left bottom)
		)
	)
	(label "B.CK1_N"
		(at 186.055 181.61 0)
		(effects
			(font
				(size 1.27 1.27)
			)
			(justify left bottom)
		)
	)
	(label "VREF"
		(at 313.055 95.25 0)
		(effects
			(font
				(size 1.27 1.27)
			)
			(justify left bottom)
		)
	)
	(label "A.~{DM2}"
		(at 78.105 100.33 0)
		(effects
			(font
				(size 1.27 1.27)
			)
			(justify left bottom)
		)
	)
	(label "VREF"
		(at 213.995 95.25 0)
		(effects
			(font
				(size 1.27 1.27)
			)
			(justify left bottom)
		)
	)
	(label "A.DQ29"
		(at 78.105 85.09 0)
		(effects
			(font
				(size 1.27 1.27)
			)
			(justify left bottom)
		)
	)
	(label "A.~{CS0}"
		(at 172.085 146.05 0)
		(effects
			(font
				(size 1.27 1.27)
			)
			(justify left bottom)
		)
	)
	(label "B.DQ16"
		(at 307.34 118.11 0)
		(effects
			(font
				(size 1.27 1.27)
			)
			(justify left bottom)
		)
	)
	(label "A.DQ21"
		(at 78.105 102.87 0)
		(effects
			(font
				(size 1.27 1.27)
			)
			(justify left bottom)
		)
	)
	(label "A.DQ3"
		(at 78.105 179.07 0)
		(effects
			(font
				(size 1.27 1.27)
			)
			(justify left bottom)
		)
	)
	(label "A.~{DM0}"
		(at 78.105 181.61 0)
		(effects
			(font
				(size 1.27 1.27)
			)
			(justify left bottom)
		)
	)
	(label "A.CK1_P"
		(at 172.085 168.91 0)
		(effects
			(font
				(size 1.27 1.27)
			)
			(justify left bottom)
		)
	)
	(label "A.DQ30"
		(at 78.105 74.93 0)
		(effects
			(font
				(size 1.27 1.27)
			)
			(justify left bottom)
		)
	)
	(label "B.DQ25"
		(at 307.34 85.09 0)
		(effects
			(font
				(size 1.27 1.27)
			)
			(justify left bottom)
		)
	)
	(label "A.CA2"
		(at 172.085 163.83 0)
		(effects
			(font
				(size 1.27 1.27)
			)
			(justify left bottom)
		)
	)
	(label "B.CA11"
		(at 186.055 77.47 0)
		(effects
			(font
				(size 1.27 1.27)
			)
			(justify left bottom)
		)
	)
	(label "VREF"
		(at 213.995 161.29 0)
		(effects
			(font
				(size 1.27 1.27)
			)
			(justify left bottom)
		)
	)
	(label "A.~{DM1}"
		(at 78.105 148.59 0)
		(effects
			(font
				(size 1.27 1.27)
			)
			(justify left bottom)
		)
	)
	(label "VREF"
		(at 82.55 95.25 0)
		(effects
			(font
				(size 1.27 1.27)
			)
			(justify left bottom)
		)
	)
	(label "B.CA12"
		(at 186.055 69.85 0)
		(effects
			(font
				(size 1.27 1.27)
			)
			(justify left bottom)
		)
	)
	(label "Control.~{RESET}"
		(at 200.025 186.69 0)
		(effects
			(font
				(size 1.27 1.27)
			)
			(justify left bottom)
		)
	)
	(label "B.DQ31"
		(at 307.34 87.63 0)
		(effects
			(font
				(size 1.27 1.27)
			)
			(justify left bottom)
		)
	)
	(label "B.DQ22"
		(at 307.34 105.41 0)
		(effects
			(font
				(size 1.27 1.27)
			)
			(justify left bottom)
		)
	)
	(label "B.DQ18"
		(at 307.34 97.79 0)
		(effects
			(font
				(size 1.27 1.27)
			)
			(justify left bottom)
		)
	)
	(label "VREF"
		(at 313.055 161.29 0)
		(effects
			(font
				(size 1.27 1.27)
			)
			(justify left bottom)
		)
	)
	(label "A.CA7"
		(at 172.085 125.73 0)
		(effects
			(font
				(size 1.27 1.27)
			)
			(justify left bottom)
		)
	)
	(label "A.DQ17"
		(at 78.105 118.11 0)
		(effects
			(font
				(size 1.27 1.27)
			)
			(justify left bottom)
		)
	)
	(label "A.~{DM3}"
		(at 78.105 69.85 0)
		(effects
			(font
				(size 1.27 1.27)
			)
			(justify left bottom)
		)
	)
	(label "B.~{DM1}"
		(at 307.34 156.21 0)
		(effects
			(font
				(size 1.27 1.27)
			)
			(justify left bottom)
		)
	)
	(label "B.~{CS1}"
		(at 186.055 184.15 0)
		(effects
			(font
				(size 1.27 1.27)
			)
			(justify left bottom)
		)
	)
	(label "B.DQS0_P"
		(at 307.34 168.91 0)
		(effects
			(font
				(size 1.27 1.27)
			)
			(justify left bottom)
		)
	)
	(label "A.DQ11"
		(at 78.105 146.05 0)
		(effects
			(font
				(size 1.27 1.27)
			)
			(justify left bottom)
		)
	)
	(label "B.DQ8"
		(at 307.34 143.51 0)
		(effects
			(font
				(size 1.27 1.27)
			)
			(justify left bottom)
		)
	)
	(label "B.~{DM0}"
		(at 307.34 173.99 0)
		(effects
			(font
				(size 1.27 1.27)
			)
			(justify left bottom)
		)
	)
	(label "B.DQ15"
		(at 307.34 128.27 0)
		(effects
			(font
				(size 1.27 1.27)
			)
			(justify left bottom)
		)
	)
	(label "A.CB2"
		(at 78.105 189.23 0)
		(effects
			(font
				(size 1.27 1.27)
			)
			(justify left bottom)
		)
	)
	(label "A.CB0"
		(at 78.105 97.79 0)
		(effects
			(font
				(size 1.27 1.27)
			)
			(justify left bottom)
		)
	)
	(label "B.DQ13"
		(at 307.34 133.35 0)
		(effects
			(font
				(size 1.27 1.27)
			)
			(justify left bottom)
		)
	)
	(label "A.DQ1"
		(at 78.105 163.83 0)
		(effects
			(font
				(size 1.27 1.27)
			)
			(justify left bottom)
		)
	)
	(label "B.CA9"
		(at 186.055 156.21 0)
		(effects
			(font
				(size 1.27 1.27)
			)
			(justify left bottom)
		)
	)
	(label "B.DQS0_N"
		(at 307.34 171.45 0)
		(effects
			(font
				(size 1.27 1.27)
			)
			(justify left bottom)
		)
	)
	(label "A.DQ0"
		(at 78.105 184.15 0)
		(effects
			(font
				(size 1.27 1.27)
			)
			(justify left bottom)
		)
	)
	(label "A.DQS0_P"
		(at 78.105 168.91 0)
		(effects
			(font
				(size 1.27 1.27)
			)
			(justify left bottom)
		)
	)
	(label "A.CA6"
		(at 172.085 120.65 0)
		(effects
			(font
				(size 1.27 1.27)
			)
			(justify left bottom)
		)
	)
	(label "B.CB0"
		(at 307.34 153.67 0)
		(effects
			(font
				(size 1.27 1.27)
			)
			(justify left bottom)
		)
	)
	(label "B.~{DM3}"
		(at 307.34 74.93 0)
		(effects
			(font
				(size 1.27 1.27)
			)
			(justify left bottom)
		)
	)
	(global_label "DAC_VREF"
		(shape input)
		(at 62.865 238.125 180)
		(fields_autoplaced yes)
		(effects
			(font
				(size 1.27 1.27)
			)
			(justify right)
		)
		(property "Intersheetrefs" "${INTERSHEET_REFS}"
			(at 51.3484 238.2044 0)
			(effects
				(font
					(size 1.27 1.27)
				)
				(justify right)
			)
		)
	)
	(hierarchical_label "A{DDR5}"
		(shape input)
		(at 168.275 99.695 180)
		(effects
			(font
				(size 1.27 1.27)
			)
			(justify right)
		)
	)
	(hierarchical_label "B{DDR5}"
		(shape input)
		(at 302.26 60.325 180)
		(effects
			(font
				(size 1.27 1.27)
			)
			(justify right)
		)
	)
	(hierarchical_label "B{DDR5}"
		(shape input)
		(at 182.245 63.5 180)
		(effects
			(font
				(size 1.27 1.27)
			)
			(justify right)
		)
	)
	(hierarchical_label "Control{DDR5}"
		(shape input)
		(at 196.215 55.88 180)
		(effects
			(font
				(size 1.27 1.27)
			)
			(justify right)
		)
	)
	(hierarchical_label "A{DDR5}"
		(shape input)
		(at 73.025 60.325 180)
		(effects
			(font
				(size 1.27 1.27)
			)
			(justify right)
		)
	)
	(symbol
		(lib_id "antmicroFPGAChips:XC7K160T-FFG676")
		(at 87.63 59.69 0)
		(unit 6)
		(exclude_from_sim no)
		(in_bom yes)
		(on_board yes)
		(dnp no)
		(fields_autoplaced yes)
		(property "Reference" "U4"
			(at 121.412 123.6294 0)
			(effects
				(font
					(size 1.27 1.27)
				)
				(justify left)
			)
		)
		(property "Value" "XC7K160T-FFG676"
			(at 121.412 126.1597 0)
			(effects
				(font
					(size 1.27 1.27)
					(thickness 0.15)
				)
				(justify left)
			)
		)
		(property "Footprint" "antmicro-footprints:BGA-676_27x27mm_Layout26x26_P1x1mm_FFG676"
			(at 156.21 62.23 0)
			(effects
				(font
					(size 1.27 1.27)
					(thickness 0.15)
				)
				(justify left bottom)
				(hide yes)
			)
		)
		(property "Datasheet" "https://docs.xilinx.com/v/u/en-US/ds180_7Series_Overview"
			(at 156.21 64.77 0)
			(effects
				(font
					(size 1.27 1.27)
					(thickness 0.15)
				)
				(justify left bottom)
				(hide yes)
			)
		)
		(property "Description" ""
			(at 87.63 59.69 0)
			(effects
				(font
					(size 1.27 1.27)
				)
			)
		)
		(property "MPN" "XC7K160T-FFG676"
			(at 87.63 59.69 0)
			(effects
				(font
					(size 1.27 1.27)
				)
				(hide yes)
			)
		)
		(property "Author" "Antmicro"
			(at 156.21 67.31 0)
			(effects
				(font
					(size 1.27 1.27)
					(thickness 0.15)
				)
				(justify left bottom)
				(hide yes)
			)
		)
		(property "License" "Apache-2.0"
			(at 156.21 69.85 0)
			(effects
				(font
					(size 1.27 1.27)
					(thickness 0.15)
				)
				(justify left bottom)
				(hide yes)
			)
		)
		(property "Manufacturer" "AMD-Xilinx"
			(at 87.63 59.69 0)
			(effects
				(font
					(size 1.27 1.27)
				)
				(hide yes)
			)
		)
		(pin "AA21"
		)
		(pin "AA22"
		)
		(pin "AA23"
		)
		(pin "AA24"
		)
		(pin "AA25"
		)
		(pin "AB21"
		)
		(pin "AB22"
		)
		(pin "AB24"
		)
		(pin "AB25"
		)
		(pin "AB26"
		)
		(pin "AC21"
		)
		(pin "AC22"
		)
		(pin "AC23"
		)
		(pin "AC24"
		)
		(pin "AC25"
		)
		(pin "AC26"
		)
		(pin "AD21"
		)
		(pin "AD22"
		)
		(pin "AD23"
		)
		(pin "AD24"
		)
		(pin "AD25"
		)
		(pin "AD26"
		)
		(pin "AE21"
		)
		(pin "AE22"
		)
		(pin "AE23"
		)
		(pin "AE25"
		)
		(pin "AE26"
		)
		(pin "AF22"
		)
		(pin "AF23"
		)
		(pin "AF24"
		)
		(pin "AF25"
		)
		(pin "AF26"
		)
		(pin "U21"
		)
		(pin "U22"
		)
		(pin "U23"
		)
		(pin "U24"
		)
		(pin "U25"
		)
		(pin "U26"
		)
		(pin "V20"
		)
		(pin "V21"
		)
		(pin "V22"
		)
		(pin "V23"
		)
		(pin "V24"
		)
		(pin "V26"
		)
		(pin "W20"
		)
		(pin "W21"
		)
		(pin "W23"
		)
		(pin "W24"
		)
		(pin "W25"
		)
		(pin "W26"
		)
		(pin "Y20"
		)
		(pin "Y21"
		)
		(pin "Y22"
		)
		(pin "Y23"
		)
		(pin "Y24"
		)
		(pin "Y25"
		)
		(pin "Y26"
		)
		(pin "K24"
		)
		(pin "K25"
		)
		(pin "K26"
		)
		(pin "L24"
		)
		(pin "L25"
		)
		(pin "M19"
		)
		(pin "M20"
		)
		(pin "M21"
		)
		(pin "M22"
		)
		(pin "M24"
		)
		(pin "M25"
		)
		(pin "M26"
		)
		(pin "N16"
		)
		(pin "N17"
		)
		(pin "N18"
		)
		(pin "N19"
		)
		(pin "N21"
		)
		(pin "N22"
		)
		(pin "N23"
		)
		(pin "N24"
		)
		(pin "N25"
		)
		(pin "N26"
		)
		(pin "P16"
		)
		(pin "P18"
		)
		(pin "P19"
		)
		(pin "P20"
		)
		(pin "P21"
		)
		(pin "P22"
		)
		(pin "P23"
		)
		(pin "P24"
		)
		(pin "P25"
		)
		(pin "P26"
		)
		(pin "R16"
		)
		(pin "R17"
		)
		(pin "R18"
		)
		(pin "R19"
		)
		(pin "R20"
		)
		(pin "R21"
		)
		(pin "R22"
		)
		(pin "R23"
		)
		(pin "R25"
		)
		(pin "R26"
		)
		(pin "T16"
		)
		(pin "T17"
		)
		(pin "T18"
		)
		(pin "T19"
		)
		(pin "T20"
		)
		(pin "T22"
		)
		(pin "T23"
		)
		(pin "T24"
		)
		(pin "T25"
		)
		(pin "T26"
		)
		(pin "U16"
		)
		(pin "U17"
		)
		(pin "U19"
		)
		(pin "U20"
		)
		(pin "A20"
		)
		(pin "A21"
		)
		(pin "A22"
		)
		(pin "A23"
		)
		(pin "A24"
		)
		(pin "A25"
		)
		(pin "B20"
		)
		(pin "B21"
		)
		(pin "B22"
		)
		(pin "B24"
		)
		(pin "B25"
		)
		(pin "B26"
		)
		(pin "C21"
		)
		(pin "C22"
		)
		(pin "C23"
		)
		(pin "C24"
		)
		(pin "C25"
		)
		(pin "C26"
		)
		(pin "D21"
		)
		(pin "D22"
		)
		(pin "D23"
		)
		(pin "D24"
		)
		(pin "D25"
		)
		(pin "D26"
		)
		(pin "E21"
		)
		(pin "E22"
		)
		(pin "E23"
		)
		(pin "E25"
		)
		(pin "E26"
		)
		(pin "F22"
		)
		(pin "F23"
		)
		(pin "F24"
		)
		(pin "F25"
		)
		(pin "F26"
		)
		(pin "G21"
		)
		(pin "G22"
		)
		(pin "G23"
		)
		(pin "G24"
		)
		(pin "G25"
		)
		(pin "G26"
		)
		(pin "H21"
		)
		(pin "H22"
		)
		(pin "H23"
		)
		(pin "H24"
		)
		(pin "H26"
		)
		(pin "J21"
		)
		(pin "J23"
		)
		(pin "J24"
		)
		(pin "J25"
		)
		(pin "J26"
		)
		(pin "K21"
		)
		(pin "K22"
		)
		(pin "K23"
		)
		(pin "L21"
		)
		(pin "L22"
		)
		(pin "L23"
		)
		(pin "A17"
		)
		(pin "A18"
		)
		(pin "A19"
		)
		(pin "B16"
		)
		(pin "B17"
		)
		(pin "B18"
		)
		(pin "B19"
		)
		(pin "C16"
		)
		(pin "C17"
		)
		(pin "C18"
		)
		(pin "C19"
		)
		(pin "D15"
		)
		(pin "D16"
		)
		(pin "D18"
		)
		(pin "D19"
		)
		(pin "D20"
		)
		(pin "E15"
		)
		(pin "E16"
		)
		(pin "E17"
		)
		(pin "E18"
		)
		(pin "E19"
		)
		(pin "E20"
		)
		(pin "F15"
		)
		(pin "F16"
		)
		(pin "F17"
		)
		(pin "F18"
		)
		(pin "F19"
		)
		(pin "F20"
		)
		(pin "G15"
		)
		(pin "G16"
		)
		(pin "G17"
		)
		(pin "G19"
		)
		(pin "G20"
		)
		(pin "H16"
		)
		(pin "H17"
		)
		(pin "H18"
		)
		(pin "H19"
		)
		(pin "H20"
		)
		(pin "J15"
		)
		(pin "J16"
		)
		(pin "J17"
		)
		(pin "J18"
		)
		(pin "J19"
		)
		(pin "J20"
		)
		(pin "K15"
		)
		(pin "K16"
		)
		(pin "K17"
		)
		(pin "K18"
		)
		(pin "K20"
		)
		(pin "L17"
		)
		(pin "L18"
		)
		(pin "L19"
		)
		(pin "L20"
		)
		(pin "M16"
		)
		(pin "M17"
		)
		(pin "M18"
		)
		(pin "A10"
		)
		(pin "A11"
		)
		(pin "A12"
		)
		(pin "A13"
		)
		(pin "A14"
		)
		(pin "A15"
		)
		(pin "A8"
		)
		(pin "A9"
		)
		(pin "B10"
		)
		(pin "B11"
		)
		(pin "B12"
		)
		(pin "B14"
		)
		(pin "B15"
		)
		(pin "B8"
		)
		(pin "B9"
		)
		(pin "C11"
		)
		(pin "C12"
		)
		(pin "C13"
		)
		(pin "C14"
		)
		(pin "C15"
		)
		(pin "C9"
		)
		(pin "D10"
		)
		(pin "D11"
		)
		(pin "D12"
		)
		(pin "D13"
		)
		(pin "D14"
		)
		(pin "D8"
		)
		(pin "D9"
		)
		(pin "E10"
		)
		(pin "E11"
		)
		(pin "E12"
		)
		(pin "E13"
		)
		(pin "E9"
		)
		(pin "F10"
		)
		(pin "F12"
		)
		(pin "F13"
		)
		(pin "F14"
		)
		(pin "F8"
		)
		(pin "F9"
		)
		(pin "G10"
		)
		(pin "G11"
		)
		(pin "G12"
		)
		(pin "G13"
		)
		(pin "G14"
		)
		(pin "G9"
		)
		(pin "H10"
		)
		(pin "H11"
		)
		(pin "H12"
		)
		(pin "H13"
		)
		(pin "H14"
		)
		(pin "H8"
		)
		(pin "H9"
		)
		(pin "J10"
		)
		(pin "J11"
		)
		(pin "J13"
		)
		(pin "J14"
		)
		(pin "J8"
		)
		(pin "AA14"
		)
		(pin "AA15"
		)
		(pin "AA17"
		)
		(pin "AA18"
		)
		(pin "AA19"
		)
		(pin "AA20"
		)
		(pin "AB14"
		)
		(pin "AB15"
		)
		(pin "AB16"
		)
		(pin "AB17"
		)
		(pin "AB18"
		)
		(pin "AB19"
		)
		(pin "AB20"
		)
		(pin "AC14"
		)
		(pin "AC15"
		)
		(pin "AC16"
		)
		(pin "AC17"
		)
		(pin "AC18"
		)
		(pin "AC19"
		)
		(pin "AD14"
		)
		(pin "AD15"
		)
		(pin "AD16"
		)
		(pin "AD18"
		)
		(pin "AD19"
		)
		(pin "AD20"
		)
		(pin "AE15"
		)
		(pin "AE16"
		)
		(pin "AE17"
		)
		(pin "AE18"
		)
		(pin "AE19"
		)
		(pin "AE20"
		)
		(pin "AF14"
		)
		(pin "AF15"
		)
		(pin "AF16"
		)
		(pin "AF17"
		)
		(pin "AF18"
		)
		(pin "AF19"
		)
		(pin "AF20"
		)
		(pin "V13"
		)
		(pin "V14"
		)
		(pin "V16"
		)
		(pin "V17"
		)
		(pin "V18"
		)
		(pin "V19"
		)
		(pin "W13"
		)
		(pin "W14"
		)
		(pin "W15"
		)
		(pin "W16"
		)
		(pin "W17"
		)
		(pin "W18"
		)
		(pin "W19"
		)
		(pin "Y14"
		)
		(pin "Y15"
		)
		(pin "Y16"
		)
		(pin "Y17"
		)
		(pin "Y18"
		)
		(pin "AA10"
		)
		(pin "AA11"
		)
		(pin "AA12"
		)
		(pin "AA13"
		)
		(pin "AA7"
		)
		(pin "AA8"
		)
		(pin "AA9"
		)
		(pin "AB10"
		)
		(pin "AB11"
		)
		(pin "AB12"
		)
		(pin "AB7"
		)
		(pin "AB8"
		)
		(pin "AB9"
		)
		(pin "AC11"
		)
		(pin "AC12"
		)
		(pin "AC13"
		)
		(pin "AC7"
		)
		(pin "AC8"
		)
		(pin "AC9"
		)
		(pin "AD10"
		)
		(pin "AD11"
		)
		(pin "AD12"
		)
		(pin "AD13"
		)
		(pin "AD8"
		)
		(pin "AD9"
		)
		(pin "AE10"
		)
		(pin "AE11"
		)
		(pin "AE12"
		)
		(pin "AE13"
		)
		(pin "AE7"
		)
		(pin "AE8"
		)
		(pin "AE9"
		)
		(pin "AF10"
		)
		(pin "AF12"
		)
		(pin "AF13"
		)
		(pin "AF7"
		)
		(pin "AF8"
		)
		(pin "AF9"
		)
		(pin "U9"
		)
		(pin "V10"
		)
		(pin "V11"
		)
		(pin "V12"
		)
		(pin "V7"
		)
		(pin "V8"
		)
		(pin "V9"
		)
		(pin "W10"
		)
		(pin "W11"
		)
		(pin "W7"
		)
		(pin "W8"
		)
		(pin "W9"
		)
		(pin "Y10"
		)
		(pin "Y11"
		)
		(pin "Y12"
		)
		(pin "Y13"
		)
		(pin "Y7"
		)
		(pin "Y8"
		)
		(pin "AA1"
		)
		(pin "AA2"
		)
		(pin "AA3"
		)
		(pin "AA4"
		)
		(pin "AA5"
		)
		(pin "AB1"
		)
		(pin "AB2"
		)
		(pin "AB4"
		)
		(pin "AB5"
		)
		(pin "AB6"
		)
		(pin "AC1"
		)
		(pin "AC2"
		)
		(pin "AC3"
		)
		(pin "AC4"
		)
		(pin "AC5"
		)
		(pin "AC6"
		)
		(pin "AD1"
		)
		(pin "AD2"
		)
		(pin "AD3"
		)
		(pin "AD4"
		)
		(pin "AD5"
		)
		(pin "AD6"
		)
		(pin "AE1"
		)
		(pin "AE2"
		)
		(pin "AE3"
		)
		(pin "AE5"
		)
		(pin "AE6"
		)
		(pin "AF2"
		)
		(pin "AF3"
		)
		(pin "AF4"
		)
		(pin "AF5"
		)
		(pin "AF6"
		)
		(pin "T7"
		)
		(pin "U1"
		)
		(pin "U2"
		)
		(pin "U3"
		)
		(pin "U4"
		)
		(pin "U5"
		)
		(pin "U6"
		)
		(pin "U7"
		)
		(pin "V1"
		)
		(pin "V2"
		)
		(pin "V3"
		)
		(pin "V4"
		)
		(pin "V6"
		)
		(pin "W1"
		)
		(pin "W3"
		)
		(pin "W4"
		)
		(pin "W5"
		)
		(pin "W6"
		)
		(pin "Y1"
		)
		(pin "Y2"
		)
		(pin "Y3"
		)
		(pin "Y4"
		)
		(pin "Y5"
		)
		(pin "Y6"
		)
		(pin "A3"
		)
		(pin "A4"
		)
		(pin "B1"
		)
		(pin "B2"
		)
		(pin "B5"
		)
		(pin "B6"
		)
		(pin "C3"
		)
		(pin "C4"
		)
		(pin "D1"
		)
		(pin "D2"
		)
		(pin "D5"
		)
		(pin "D6"
		)
		(pin "E3"
		)
		(pin "E4"
		)
		(pin "F1"
		)
		(pin "F2"
		)
		(pin "F5"
		)
		(pin "F6"
		)
		(pin "G3"
		)
		(pin "G4"
		)
		(pin "H1"
		)
		(pin "H2"
		)
		(pin "H5"
		)
		(pin "H6"
		)
		(pin "J3"
		)
		(pin "J4"
		)
		(pin "K1"
		)
		(pin "K2"
		)
		(pin "K5"
		)
		(pin "K6"
		)
		(pin "L3"
		)
		(pin "L4"
		)
		(pin "M1"
		)
		(pin "M2"
		)
		(pin "N3"
		)
		(pin "N4"
		)
		(pin "P1"
		)
		(pin "P2"
		)
		(pin "R3"
		)
		(pin "R4"
		)
		(pin "A1"
		)
		(pin "A16"
		)
		(pin "A2"
		)
		(pin "A26"
		)
		(pin "A5"
		)
		(pin "A6"
		)
		(pin "A7"
		)
		(pin "AA16"
		)
		(pin "AA26"
		)
		(pin "AA6"
		)
		(pin "AB13"
		)
		(pin "AB23"
		)
		(pin "AB3"
		)
		(pin "AC10"
		)
		(pin "AC20"
		)
		(pin "AD17"
		)
		(pin "AD7"
		)
		(pin "AE14"
		)
		(pin "AE24"
		)
		(pin "AE4"
		)
		(pin "AF1"
		)
		(pin "AF11"
		)
		(pin "AF21"
		)
		(pin "B13"
		)
		(pin "B23"
		)
		(pin "B3"
		)
		(pin "B4"
		)
		(pin "B7"
		)
		(pin "C1"
		)
		(pin "C10"
		)
		(pin "C2"
		)
		(pin "C20"
		)
		(pin "C5"
		)
		(pin "C6"
		)
		(pin "C7"
		)
		(pin "D17"
		)
		(pin "D3"
		)
		(pin "D4"
		)
		(pin "D7"
		)
		(pin "E1"
		)
		(pin "E14"
		)
		(pin "E2"
		)
		(pin "E24"
		)
		(pin "E5"
		)
		(pin "E6"
		)
		(pin "E7"
		)
		(pin "E8"
		)
		(pin "F11"
		)
		(pin "F21"
		)
		(pin "F3"
		)
		(pin "F4"
		)
		(pin "F7"
		)
		(pin "G1"
		)
		(pin "G18"
		)
		(pin "G2"
		)
		(pin "G5"
		)
		(pin "G6"
		)
		(pin "G8"
		)
		(pin "H15"
		)
		(pin "H25"
		)
		(pin "H3"
		)
		(pin "H4"
		)
		(pin "H7"
		)
		(pin "J1"
		)
		(pin "J12"
		)
		(pin "J2"
		)
		(pin "J22"
		)
		(pin "J5"
		)
		(pin "J6"
		)
		(pin "J9"
		)
		(pin "K10"
		)
		(pin "K11"
		)
		(pin "K12"
		)
		(pin "K13"
		)
		(pin "K14"
		)
		(pin "K19"
		)
		(pin "K3"
		)
		(pin "K4"
		)
		(pin "K7"
		)
		(pin "K8"
		)
		(pin "K9"
		)
		(pin "L1"
		)
		(pin "L10"
		)
		(pin "L11"
		)
		(pin "L12"
		)
		(pin "L13"
		)
		(pin "L14"
		)
		(pin "L15"
		)
		(pin "L16"
		)
		(pin "L2"
		)
		(pin "L26"
		)
		(pin "L5"
		)
		(pin "L6"
		)
		(pin "L9"
		)
		(pin "M10"
		)
		(pin "M11"
		)
		(pin "M12"
		)
		(pin "M13"
		)
		(pin "M14"
		)
		(pin "M15"
		)
		(pin "M23"
		)
		(pin "M3"
		)
		(pin "M4"
		)
		(pin "M5"
		)
		(pin "M6"
		)
		(pin "M7"
		)
		(pin "M8"
		)
		(pin "M9"
		)
		(pin "N1"
		)
		(pin "N10"
		)
		(pin "N13"
		)
		(pin "N14"
		)
		(pin "N15"
		)
		(pin "N2"
		)
		(pin "N20"
		)
		(pin "N5"
		)
		(pin "N6"
		)
		(pin "N7"
		)
		(pin "N9"
		)
		(pin "P10"
		)
		(pin "P13"
		)
		(pin "P14"
		)
		(pin "P15"
		)
		(pin "P17"
		)
		(pin "P3"
		)
		(pin "P4"
		)
		(pin "P8"
		)
		(pin "P9"
		)
		(pin "R1"
		)
		(pin "R10"
		)
		(pin "R13"
		)
		(pin "R14"
		)
		(pin "R15"
		)
		(pin "R2"
		)
		(pin "R24"
		)
		(pin "R5"
		)
		(pin "R8"
		)
		(pin "R9"
		)
		(pin "T1"
		)
		(pin "T10"
		)
		(pin "T11"
		)
		(pin "T12"
		)
		(pin "T13"
		)
		(pin "T14"
		)
		(pin "T15"
		)
		(pin "T21"
		)
		(pin "T3"
		)
		(pin "T4"
		)
		(pin "T8"
		)
		(pin "T9"
		)
		(pin "U10"
		)
		(pin "U11"
		)
		(pin "U12"
		)
		(pin "U13"
		)
		(pin "U14"
		)
		(pin "U15"
		)
		(pin "U18"
		)
		(pin "U8"
		)
		(pin "V15"
		)
		(pin "V25"
		)
		(pin "V5"
		)
		(pin "W12"
		)
		(pin "W2"
		)
		(pin "W22"
		)
		(pin "Y19"
		)
		(pin "Y9"
		)
		(pin "C8"
		)
		(pin "G7"
		)
		(pin "J7"
		)
		(pin "L7"
		)
		(pin "L8"
		)
		(pin "N11"
		)
		(pin "N12"
		)
		(pin "N8"
		)
		(pin "P11"
		)
		(pin "P12"
		)
		(pin "P5"
		)
		(pin "P6"
		)
		(pin "P7"
		)
		(pin "R11"
		)
		(pin "R12"
		)
		(pin "R6"
		)
		(pin "R7"
		)
		(pin "T2"
		)
		(pin "T5"
		)
		(pin "T6"
		)
		(instances
			(project "sodimm-ddr5-tester"
				(path ""
					(reference "U4")
					(unit 6)
				)
			)
		)
	)
	(symbol
		(lib_id "antmicropower:GND")
		(at 79.375 253.365 0)
		(mirror y)
		(unit 1)
		(exclude_from_sim no)
		(in_bom yes)
		(on_board yes)
		(dnp no)
		(fields_autoplaced yes)
		(property "Reference" "#PWR0280"
			(at 79.375 259.715 0)
			(effects
				(font
					(size 1.27 1.27)
				)
				(hide yes)
			)
		)
		(property "Value" "GND"
			(at 81.28 254.635 0)
			(effects
				(font
					(size 1.27 1.27)
					(thickness 0.15)
				)
				(justify right)
			)
		)
		(property "Footprint" ""
			(at 70.485 260.985 0)
			(effects
				(font
					(size 1.27 1.27)
					(thickness 0.15)
				)
				(justify left bottom)
				(hide yes)
			)
		)
		(property "Datasheet" ""
			(at 70.485 266.065 0)
			(effects
				(font
					(size 1.27 1.27)
					(thickness 0.15)
				)
				(justify left bottom)
				(hide yes)
			)
		)
		(property "Description" ""
			(at 70.485 268.605 0)
			(effects
				(font
					(size 1.27 1.27)
				)
				(justify left bottom)
				(hide yes)
			)
		)
		(property "Author" "Antmicro"
			(at 70.485 260.985 0)
			(effects
				(font
					(size 1.27 1.27)
					(thickness 0.15)
				)
				(justify left bottom)
				(hide yes)
			)
		)
		(property "License" "Apache-2.0"
			(at 70.485 263.525 0)
			(effects
				(font
					(size 1.27 1.27)
					(thickness 0.15)
				)
				(justify left bottom)
				(hide yes)
			)
		)
		(pin "1"
		)
		(instances
			(project "sodimm-ddr5-tester"
				(path ""
					(reference "#PWR0280")
					(unit 1)
				)
			)
		)
	)
	(symbol
		(lib_id "antmicropower:GND")
		(at 72.39 253.365 0)
		(mirror y)
		(unit 1)
		(exclude_from_sim no)
		(in_bom yes)
		(on_board yes)
		(dnp no)
		(fields_autoplaced yes)
		(property "Reference" "#PWR0279"
			(at 72.39 259.715 0)
			(effects
				(font
					(size 1.27 1.27)
				)
				(hide yes)
			)
		)
		(property "Value" "GND"
			(at 74.93 254.635 0)
			(effects
				(font
					(size 1.27 1.27)
					(thickness 0.15)
				)
				(justify right)
			)
		)
		(property "Footprint" ""
			(at 63.5 260.985 0)
			(effects
				(font
					(size 1.27 1.27)
					(thickness 0.15)
				)
				(justify left bottom)
				(hide yes)
			)
		)
		(property "Datasheet" ""
			(at 63.5 266.065 0)
			(effects
				(font
					(size 1.27 1.27)
					(thickness 0.15)
				)
				(justify left bottom)
				(hide yes)
			)
		)
		(property "Description" ""
			(at 63.5 268.605 0)
			(effects
				(font
					(size 1.27 1.27)
				)
				(justify left bottom)
				(hide yes)
			)
		)
		(property "Author" "Antmicro"
			(at 63.5 260.985 0)
			(effects
				(font
					(size 1.27 1.27)
					(thickness 0.15)
				)
				(justify left bottom)
				(hide yes)
			)
		)
		(property "License" "Apache-2.0"
			(at 63.5 263.525 0)
			(effects
				(font
					(size 1.27 1.27)
					(thickness 0.15)
				)
				(justify left bottom)
				(hide yes)
			)
		)
		(pin "1"
		)
		(instances
			(project "sodimm-ddr5-tester"
				(path ""
					(reference "#PWR0279")
					(unit 1)
				)
			)
		)
	)
	(symbol
		(lib_id "antmicroCapacitors0402:C_100n_0402")
		(at 79.375 248.285 90)
		(mirror x)
		(unit 1)
		(exclude_from_sim no)
		(in_bom yes)
		(on_board yes)
		(dnp no)
		(property "Reference" "C168"
			(at 80.01 248.92 90)
			(effects
				(font
					(size 1.27 1.27)
				)
				(justify right)
			)
		)
		(property "Value" "C_100n_0402"
			(at 89.535 268.605 0)
			(effects
				(font
					(size 1.27 1.27)
					(thickness 0.15)
				)
				(justify left bottom)
				(hide yes)
			)
		)
		(property "Footprint" "antmicro-footprints:C_0402_1005Metric"
			(at 92.075 268.605 0)
			(effects
				(font
					(size 1.27 1.27)
					(thickness 0.15)
				)
				(justify left bottom)
				(hide yes)
			)
		)
		(property "Datasheet" "https://www.murata.com/products/productdetail?partno=GRM155R61H104KE14%23"
			(at 94.615 268.605 0)
			(effects
				(font
					(size 1.27 1.27)
					(thickness 0.15)
				)
				(justify left bottom)
				(hide yes)
			)
		)
		(property "Description" ""
			(at 79.375 248.285 0)
			(effects
				(font
					(size 1.27 1.27)
				)
			)
		)
		(property "Manufacturer" "Murata"
			(at 99.695 268.605 0)
			(effects
				(font
					(size 1.27 1.27)
					(thickness 0.15)
				)
				(justify left bottom)
				(hide yes)
			)
		)
		(property "MPN" "GRM155R61H104KE14D"
			(at 97.155 268.605 0)
			(effects
				(font
					(size 1.27 1.27)
					(thickness 0.15)
				)
				(justify left bottom)
				(hide yes)
			)
		)
		(property "Val" "100n"
			(at 80.01 252.73 90)
			(effects
				(font
					(size 1.27 1.27)
					(thickness 0.15)
				)
				(justify right)
			)
		)
		(property "License" "Apache-2.0"
			(at 102.235 268.605 0)
			(effects
				(font
					(size 1.27 1.27)
					(thickness 0.15)
				)
				(justify left bottom)
				(hide yes)
			)
		)
		(property "Author" "Antmicro"
			(at 104.775 268.605 0)
			(effects
				(font
					(size 1.27 1.27)
					(thickness 0.15)
				)
				(justify left bottom)
				(hide yes)
			)
		)
		(property "Voltage" "50V"
			(at 107.315 268.605 0)
			(effects
				(font
					(size 1.27 1.27)
				)
				(justify left bottom)
				(hide yes)
			)
		)
		(property "Dielectric" "X5R"
			(at 109.855 268.605 0)
			(effects
				(font
					(size 1.27 1.27)
				)
				(justify left bottom)
				(hide yes)
			)
		)
		(pin "1"
		)
		(pin "2"
		)
		(instances
			(project "sodimm-ddr5-tester"
				(path ""
					(reference "C168")
					(unit 1)
				)
			)
		)
	)
	(symbol
		(lib_id "antmicroCapacitors0402:C_100n_0402")
		(at 72.39 248.285 90)
		(mirror x)
		(unit 1)
		(exclude_from_sim no)
		(in_bom yes)
		(on_board yes)
		(dnp no)
		(property "Reference" "C167"
			(at 73.025 248.92 90)
			(effects
				(font
					(size 1.27 1.27)
				)
				(justify right)
			)
		)
		(property "Value" "C_100n_0402"
			(at 82.55 268.605 0)
			(effects
				(font
					(size 1.27 1.27)
					(thickness 0.15)
				)
				(justify left bottom)
				(hide yes)
			)
		)
		(property "Footprint" "antmicro-footprints:C_0402_1005Metric"
			(at 85.09 268.605 0)
			(effects
				(font
					(size 1.27 1.27)
					(thickness 0.15)
				)
				(justify left bottom)
				(hide yes)
			)
		)
		(property "Datasheet" "https://www.murata.com/products/productdetail?partno=GRM155R61H104KE14%23"
			(at 87.63 268.605 0)
			(effects
				(font
					(size 1.27 1.27)
					(thickness 0.15)
				)
				(justify left bottom)
				(hide yes)
			)
		)
		(property "Description" ""
			(at 72.39 248.285 0)
			(effects
				(font
					(size 1.27 1.27)
				)
			)
		)
		(property "Manufacturer" "Murata"
			(at 92.71 268.605 0)
			(effects
				(font
					(size 1.27 1.27)
					(thickness 0.15)
				)
				(justify left bottom)
				(hide yes)
			)
		)
		(property "MPN" "GRM155R61H104KE14D"
			(at 90.17 268.605 0)
			(effects
				(font
					(size 1.27 1.27)
					(thickness 0.15)
				)
				(justify left bottom)
				(hide yes)
			)
		)
		(property "Val" "100n"
			(at 73.025 252.73 90)
			(effects
				(font
					(size 1.27 1.27)
					(thickness 0.15)
				)
				(justify right)
			)
		)
		(property "License" "Apache-2.0"
			(at 95.25 268.605 0)
			(effects
				(font
					(size 1.27 1.27)
					(thickness 0.15)
				)
				(justify left bottom)
				(hide yes)
			)
		)
		(property "Author" "Antmicro"
			(at 97.79 268.605 0)
			(effects
				(font
					(size 1.27 1.27)
					(thickness 0.15)
				)
				(justify left bottom)
				(hide yes)
			)
		)
		(property "Voltage" "50V"
			(at 100.33 268.605 0)
			(effects
				(font
					(size 1.27 1.27)
				)
				(justify left bottom)
				(hide yes)
			)
		)
		(property "Dielectric" "X5R"
			(at 102.87 268.605 0)
			(effects
				(font
					(size 1.27 1.27)
				)
				(justify left bottom)
				(hide yes)
			)
		)
		(pin "1"
		)
		(pin "2"
		)
		(instances
			(project "sodimm-ddr5-tester"
				(path ""
					(reference "C167")
					(unit 1)
				)
			)
		)
	)
	(symbol
		(lib_id "antmicropower:GND")
		(at 34.29 253.365 0)
		(mirror y)
		(unit 1)
		(exclude_from_sim no)
		(in_bom yes)
		(on_board yes)
		(dnp no)
		(fields_autoplaced yes)
		(property "Reference" "#PWR0277"
			(at 34.29 259.715 0)
			(effects
				(font
					(size 1.27 1.27)
				)
				(hide yes)
			)
		)
		(property "Value" "GND"
			(at 36.83 254.635 0)
			(effects
				(font
					(size 1.27 1.27)
					(thickness 0.15)
				)
				(justify right)
			)
		)
		(property "Footprint" ""
			(at 25.4 260.985 0)
			(effects
				(font
					(size 1.27 1.27)
					(thickness 0.15)
				)
				(justify left bottom)
				(hide yes)
			)
		)
		(property "Datasheet" ""
			(at 25.4 266.065 0)
			(effects
				(font
					(size 1.27 1.27)
					(thickness 0.15)
				)
				(justify left bottom)
				(hide yes)
			)
		)
		(property "Description" ""
			(at 25.4 268.605 0)
			(effects
				(font
					(size 1.27 1.27)
				)
				(justify left bottom)
				(hide yes)
			)
		)
		(property "Author" "Antmicro"
			(at 25.4 260.985 0)
			(effects
				(font
					(size 1.27 1.27)
					(thickness 0.15)
				)
				(justify left bottom)
				(hide yes)
			)
		)
		(property "License" "Apache-2.0"
			(at 25.4 263.525 0)
			(effects
				(font
					(size 1.27 1.27)
					(thickness 0.15)
				)
				(justify left bottom)
				(hide yes)
			)
		)
		(pin "1"
		)
		(instances
			(project "sodimm-ddr5-tester"
				(path ""
					(reference "#PWR0277")
					(unit 1)
				)
			)
		)
	)
	(symbol
		(lib_id "antmicropower:GND")
		(at 140.335 255.905 0)
		(mirror y)
		(unit 1)
		(exclude_from_sim no)
		(in_bom yes)
		(on_board yes)
		(dnp no)
		(fields_autoplaced yes)
		(property "Reference" "#PWR0281"
			(at 140.335 262.255 0)
			(effects
				(font
					(size 1.27 1.27)
				)
				(hide yes)
			)
		)
		(property "Value" "GND"
			(at 142.24 257.175 0)
			(effects
				(font
					(size 1.27 1.27)
					(thickness 0.15)
				)
				(justify right)
			)
		)
		(property "Footprint" ""
			(at 131.445 263.525 0)
			(effects
				(font
					(size 1.27 1.27)
					(thickness 0.15)
				)
				(justify left bottom)
				(hide yes)
			)
		)
		(property "Datasheet" ""
			(at 131.445 268.605 0)
			(effects
				(font
					(size 1.27 1.27)
					(thickness 0.15)
				)
				(justify left bottom)
				(hide yes)
			)
		)
		(property "Description" ""
			(at 131.445 271.145 0)
			(effects
				(font
					(size 1.27 1.27)
				)
				(justify left bottom)
				(hide yes)
			)
		)
		(property "Author" "Antmicro"
			(at 131.445 263.525 0)
			(effects
				(font
					(size 1.27 1.27)
					(thickness 0.15)
				)
				(justify left bottom)
				(hide yes)
			)
		)
		(property "License" "Apache-2.0"
			(at 131.445 266.065 0)
			(effects
				(font
					(size 1.27 1.27)
					(thickness 0.15)
				)
				(justify left bottom)
				(hide yes)
			)
		)
		(pin "1"
		)
		(instances
			(project "sodimm-ddr5-tester"
				(path ""
					(reference "#PWR0281")
					(unit 1)
				)
			)
		)
	)
	(symbol
		(lib_name "R_80R6_0402_EIA_1")
		(lib_id "antmicroResistors0402:R_80R6_0402_EIA")
		(at 131.445 245.745 0)
		(unit 1)
		(exclude_from_sim no)
		(in_bom yes)
		(on_board yes)
		(dnp no)
		(fields_autoplaced yes)
		(property "Reference" "R133"
			(at 133.985 241.171 0)
			(effects
				(font
					(size 1.27 1.27)
					(thickness 0.15)
				)
			)
		)
		(property "Value" "R_80R6_0402_EIA"
			(at 151.765 258.445 0)
			(effects
				(font
					(size 1.27 1.27)
					(thickness 0.15)
				)
				(justify left bottom)
				(hide yes)
			)
		)
		(property "Footprint" "antmicro-footprints:R_0402_1005Metric_EIA"
			(at 151.765 260.985 0)
			(effects
				(font
					(size 1.27 1.27)
					(thickness 0.15)
				)
				(justify left bottom)
				(hide yes)
			)
		)
		(property "Datasheet" "https://www.bourns.com/docs/product-datasheets/cr.pdf"
			(at 151.765 263.525 0)
			(effects
				(font
					(size 1.27 1.27)
					(thickness 0.15)
				)
				(justify left bottom)
				(hide yes)
			)
		)
		(property "Description" ""
			(at 131.445 245.745 0)
			(effects
				(font
					(size 1.27 1.27)
				)
			)
		)
		(property "MPN" "MC00625W0402180R6"
			(at 151.765 266.065 0)
			(effects
				(font
					(size 1.27 1.27)
					(thickness 0.15)
				)
				(justify left bottom)
				(hide yes)
			)
		)
		(property "Manufacturer" "Multicomp Pro"
			(at 151.765 268.605 0)
			(effects
				(font
					(size 1.27 1.27)
					(thickness 0.15)
				)
				(justify left bottom)
				(hide yes)
			)
		)
		(property "License" "Apache-2.0"
			(at 151.765 271.145 0)
			(effects
				(font
					(size 1.27 1.27)
					(thickness 0.15)
				)
				(justify left bottom)
				(hide yes)
			)
		)
		(property "Author" "Antmicro"
			(at 151.765 273.685 0)
			(effects
				(font
					(size 1.27 1.27)
					(thickness 0.15)
				)
				(justify left bottom)
				(hide yes)
			)
		)
		(property "Val" "80R6"
			(at 133.985 243.6947 0)
			(effects
				(font
					(size 1.27 1.27)
					(thickness 0.15)
				)
			)
		)
		(property "Tolerance" "1%"
			(at 151.765 255.905 0)
			(effects
				(font
					(size 1.27 1.27)
				)
				(justify left bottom)
				(hide yes)
			)
		)
		(pin "1"
		)
		(pin "2"
		)
		(instances
			(project "sodimm-ddr5-tester"
				(path ""
					(reference "R133")
					(unit 1)
				)
			)
		)
	)
	(symbol
		(lib_id "antmicroResistors0402:R_80R6_0402_EIA")
		(at 131.445 254 0)
		(unit 1)
		(exclude_from_sim no)
		(in_bom yes)
		(on_board yes)
		(dnp no)
		(fields_autoplaced yes)
		(property "Reference" "R134"
			(at 133.985 249.426 0)
			(effects
				(font
					(size 1.27 1.27)
					(thickness 0.15)
				)
			)
		)
		(property "Value" "R_80R6_0402_EIA"
			(at 151.765 266.7 0)
			(effects
				(font
					(size 1.27 1.27)
					(thickness 0.15)
				)
				(justify left bottom)
				(hide yes)
			)
		)
		(property "Footprint" "antmicro-footprints:R_0402_1005Metric_EIA"
			(at 151.765 269.24 0)
			(effects
				(font
					(size 1.27 1.27)
					(thickness 0.15)
				)
				(justify left bottom)
				(hide yes)
			)
		)
		(property "Datasheet" "https://www.bourns.com/docs/product-datasheets/cr.pdf"
			(at 151.765 271.78 0)
			(effects
				(font
					(size 1.27 1.27)
					(thickness 0.15)
				)
				(justify left bottom)
				(hide yes)
			)
		)
		(property "Description" ""
			(at 131.445 254 0)
			(effects
				(font
					(size 1.27 1.27)
				)
			)
		)
		(property "MPN" "MC00625W0402180R6"
			(at 151.765 274.32 0)
			(effects
				(font
					(size 1.27 1.27)
					(thickness 0.15)
				)
				(justify left bottom)
				(hide yes)
			)
		)
		(property "Manufacturer" "Multicomp Pro"
			(at 151.765 276.86 0)
			(effects
				(font
					(size 1.27 1.27)
					(thickness 0.15)
				)
				(justify left bottom)
				(hide yes)
			)
		)
		(property "License" "Apache-2.0"
			(at 151.765 279.4 0)
			(effects
				(font
					(size 1.27 1.27)
					(thickness 0.15)
				)
				(justify left bottom)
				(hide yes)
			)
		)
		(property "Author" "Antmicro"
			(at 151.765 281.94 0)
			(effects
				(font
					(size 1.27 1.27)
					(thickness 0.15)
				)
				(justify left bottom)
				(hide yes)
			)
		)
		(property "Val" "80R6"
			(at 133.985 251.9497 0)
			(effects
				(font
					(size 1.27 1.27)
					(thickness 0.15)
				)
			)
		)
		(property "Tolerance" "1%"
			(at 151.765 264.16 0)
			(effects
				(font
					(size 1.27 1.27)
				)
				(justify left bottom)
				(hide yes)
			)
		)
		(pin "1"
		)
		(pin "2"
		)
		(instances
			(project "sodimm-ddr5-tester"
				(path ""
					(reference "R134")
					(unit 1)
				)
			)
		)
	)
	(symbol
		(lib_id "antmicropower:+1V1")
		(at 142.24 243.84 0)
		(unit 1)
		(exclude_from_sim no)
		(in_bom yes)
		(on_board yes)
		(dnp no)
		(fields_autoplaced yes)
		(property "Reference" "#PWR0282"
			(at 142.24 247.65 0)
			(effects
				(font
					(size 1.27 1.27)
				)
				(hide yes)
			)
		)
		(property "Value" "+1V1"
			(at 142.24 240.284 0)
			(effects
				(font
					(size 1.27 1.27)
				)
			)
		)
		(property "Footprint" ""
			(at 142.24 243.84 0)
			(effects
				(font
					(size 1.27 1.27)
				)
				(hide yes)
			)
		)
		(property "Datasheet" ""
			(at 142.24 243.84 0)
			(effects
				(font
					(size 1.27 1.27)
				)
				(hide yes)
			)
		)
		(property "Description" ""
			(at 142.24 243.84 0)
			(effects
				(font
					(size 1.27 1.27)
				)
			)
		)
		(pin "1"
		)
		(instances
			(project "sodimm-ddr5-tester"
				(path ""
					(reference "#PWR0282")
					(unit 1)
				)
			)
		)
	)
	(symbol
		(lib_id "antmicroFPGAChips:XC7K160T-FFG676")
		(at 218.44 59.69 0)
		(unit 7)
		(exclude_from_sim no)
		(in_bom yes)
		(on_board yes)
		(dnp no)
		(fields_autoplaced yes)
		(property "Reference" "U4"
			(at 252.222 123.6294 0)
			(effects
				(font
					(size 1.27 1.27)
				)
				(justify left)
			)
		)
		(property "Value" "XC7K160T-FFG676"
			(at 252.222 126.1597 0)
			(effects
				(font
					(size 1.27 1.27)
					(thickness 0.15)
				)
				(justify left)
			)
		)
		(property "Footprint" "antmicro-footprints:BGA-676_27x27mm_Layout26x26_P1x1mm_FFG676"
			(at 287.02 62.23 0)
			(effects
				(font
					(size 1.27 1.27)
					(thickness 0.15)
				)
				(justify left bottom)
				(hide yes)
			)
		)
		(property "Datasheet" "https://docs.xilinx.com/v/u/en-US/ds180_7Series_Overview"
			(at 287.02 64.77 0)
			(effects
				(font
					(size 1.27 1.27)
					(thickness 0.15)
				)
				(justify left bottom)
				(hide yes)
			)
		)
		(property "Description" ""
			(at 218.44 59.69 0)
			(effects
				(font
					(size 1.27 1.27)
				)
			)
		)
		(property "MPN" "XC7K160T-FFG676"
			(at 218.44 59.69 0)
			(effects
				(font
					(size 1.27 1.27)
				)
				(hide yes)
			)
		)
		(property "Author" "Antmicro"
			(at 287.02 67.31 0)
			(effects
				(font
					(size 1.27 1.27)
					(thickness 0.15)
				)
				(justify left bottom)
				(hide yes)
			)
		)
		(property "License" "Apache-2.0"
			(at 287.02 69.85 0)
			(effects
				(font
					(size 1.27 1.27)
					(thickness 0.15)
				)
				(justify left bottom)
				(hide yes)
			)
		)
		(property "Manufacturer" "AMD-Xilinx"
			(at 218.44 59.69 0)
			(effects
				(font
					(size 1.27 1.27)
				)
				(hide yes)
			)
		)
		(pin "AA21"
		)
		(pin "AA22"
		)
		(pin "AA23"
		)
		(pin "AA24"
		)
		(pin "AA25"
		)
		(pin "AB21"
		)
		(pin "AB22"
		)
		(pin "AB24"
		)
		(pin "AB25"
		)
		(pin "AB26"
		)
		(pin "AC21"
		)
		(pin "AC22"
		)
		(pin "AC23"
		)
		(pin "AC24"
		)
		(pin "AC25"
		)
		(pin "AC26"
		)
		(pin "AD21"
		)
		(pin "AD22"
		)
		(pin "AD23"
		)
		(pin "AD24"
		)
		(pin "AD25"
		)
		(pin "AD26"
		)
		(pin "AE21"
		)
		(pin "AE22"
		)
		(pin "AE23"
		)
		(pin "AE25"
		)
		(pin "AE26"
		)
		(pin "AF22"
		)
		(pin "AF23"
		)
		(pin "AF24"
		)
		(pin "AF25"
		)
		(pin "AF26"
		)
		(pin "U21"
		)
		(pin "U22"
		)
		(pin "U23"
		)
		(pin "U24"
		)
		(pin "U25"
		)
		(pin "U26"
		)
		(pin "V20"
		)
		(pin "V21"
		)
		(pin "V22"
		)
		(pin "V23"
		)
		(pin "V24"
		)
		(pin "V26"
		)
		(pin "W20"
		)
		(pin "W21"
		)
		(pin "W23"
		)
		(pin "W24"
		)
		(pin "W25"
		)
		(pin "W26"
		)
		(pin "Y20"
		)
		(pin "Y21"
		)
		(pin "Y22"
		)
		(pin "Y23"
		)
		(pin "Y24"
		)
		(pin "Y25"
		)
		(pin "Y26"
		)
		(pin "K24"
		)
		(pin "K25"
		)
		(pin "K26"
		)
		(pin "L24"
		)
		(pin "L25"
		)
		(pin "M19"
		)
		(pin "M20"
		)
		(pin "M21"
		)
		(pin "M22"
		)
		(pin "M24"
		)
		(pin "M25"
		)
		(pin "M26"
		)
		(pin "N16"
		)
		(pin "N17"
		)
		(pin "N18"
		)
		(pin "N19"
		)
		(pin "N21"
		)
		(pin "N22"
		)
		(pin "N23"
		)
		(pin "N24"
		)
		(pin "N25"
		)
		(pin "N26"
		)
		(pin "P16"
		)
		(pin "P18"
		)
		(pin "P19"
		)
		(pin "P20"
		)
		(pin "P21"
		)
		(pin "P22"
		)
		(pin "P23"
		)
		(pin "P24"
		)
		(pin "P25"
		)
		(pin "P26"
		)
		(pin "R16"
		)
		(pin "R17"
		)
		(pin "R18"
		)
		(pin "R19"
		)
		(pin "R20"
		)
		(pin "R21"
		)
		(pin "R22"
		)
		(pin "R23"
		)
		(pin "R25"
		)
		(pin "R26"
		)
		(pin "T16"
		)
		(pin "T17"
		)
		(pin "T18"
		)
		(pin "T19"
		)
		(pin "T20"
		)
		(pin "T22"
		)
		(pin "T23"
		)
		(pin "T24"
		)
		(pin "T25"
		)
		(pin "T26"
		)
		(pin "U16"
		)
		(pin "U17"
		)
		(pin "U19"
		)
		(pin "U20"
		)
		(pin "A20"
		)
		(pin "A21"
		)
		(pin "A22"
		)
		(pin "A23"
		)
		(pin "A24"
		)
		(pin "A25"
		)
		(pin "B20"
		)
		(pin "B21"
		)
		(pin "B22"
		)
		(pin "B24"
		)
		(pin "B25"
		)
		(pin "B26"
		)
		(pin "C21"
		)
		(pin "C22"
		)
		(pin "C23"
		)
		(pin "C24"
		)
		(pin "C25"
		)
		(pin "C26"
		)
		(pin "D21"
		)
		(pin "D22"
		)
		(pin "D23"
		)
		(pin "D24"
		)
		(pin "D25"
		)
		(pin "D26"
		)
		(pin "E21"
		)
		(pin "E22"
		)
		(pin "E23"
		)
		(pin "E25"
		)
		(pin "E26"
		)
		(pin "F22"
		)
		(pin "F23"
		)
		(pin "F24"
		)
		(pin "F25"
		)
		(pin "F26"
		)
		(pin "G21"
		)
		(pin "G22"
		)
		(pin "G23"
		)
		(pin "G24"
		)
		(pin "G25"
		)
		(pin "G26"
		)
		(pin "H21"
		)
		(pin "H22"
		)
		(pin "H23"
		)
		(pin "H24"
		)
		(pin "H26"
		)
		(pin "J21"
		)
		(pin "J23"
		)
		(pin "J24"
		)
		(pin "J25"
		)
		(pin "J26"
		)
		(pin "K21"
		)
		(pin "K22"
		)
		(pin "K23"
		)
		(pin "L21"
		)
		(pin "L22"
		)
		(pin "L23"
		)
		(pin "A17"
		)
		(pin "A18"
		)
		(pin "A19"
		)
		(pin "B16"
		)
		(pin "B17"
		)
		(pin "B18"
		)
		(pin "B19"
		)
		(pin "C16"
		)
		(pin "C17"
		)
		(pin "C18"
		)
		(pin "C19"
		)
		(pin "D15"
		)
		(pin "D16"
		)
		(pin "D18"
		)
		(pin "D19"
		)
		(pin "D20"
		)
		(pin "E15"
		)
		(pin "E16"
		)
		(pin "E17"
		)
		(pin "E18"
		)
		(pin "E19"
		)
		(pin "E20"
		)
		(pin "F15"
		)
		(pin "F16"
		)
		(pin "F17"
		)
		(pin "F18"
		)
		(pin "F19"
		)
		(pin "F20"
		)
		(pin "G15"
		)
		(pin "G16"
		)
		(pin "G17"
		)
		(pin "G19"
		)
		(pin "G20"
		)
		(pin "H16"
		)
		(pin "H17"
		)
		(pin "H18"
		)
		(pin "H19"
		)
		(pin "H20"
		)
		(pin "J15"
		)
		(pin "J16"
		)
		(pin "J17"
		)
		(pin "J18"
		)
		(pin "J19"
		)
		(pin "J20"
		)
		(pin "K15"
		)
		(pin "K16"
		)
		(pin "K17"
		)
		(pin "K18"
		)
		(pin "K20"
		)
		(pin "L17"
		)
		(pin "L18"
		)
		(pin "L19"
		)
		(pin "L20"
		)
		(pin "M16"
		)
		(pin "M17"
		)
		(pin "M18"
		)
		(pin "A10"
		)
		(pin "A11"
		)
		(pin "A12"
		)
		(pin "A13"
		)
		(pin "A14"
		)
		(pin "A15"
		)
		(pin "A8"
		)
		(pin "A9"
		)
		(pin "B10"
		)
		(pin "B11"
		)
		(pin "B12"
		)
		(pin "B14"
		)
		(pin "B15"
		)
		(pin "B8"
		)
		(pin "B9"
		)
		(pin "C11"
		)
		(pin "C12"
		)
		(pin "C13"
		)
		(pin "C14"
		)
		(pin "C15"
		)
		(pin "C9"
		)
		(pin "D10"
		)
		(pin "D11"
		)
		(pin "D12"
		)
		(pin "D13"
		)
		(pin "D14"
		)
		(pin "D8"
		)
		(pin "D9"
		)
		(pin "E10"
		)
		(pin "E11"
		)
		(pin "E12"
		)
		(pin "E13"
		)
		(pin "E9"
		)
		(pin "F10"
		)
		(pin "F12"
		)
		(pin "F13"
		)
		(pin "F14"
		)
		(pin "F8"
		)
		(pin "F9"
		)
		(pin "G10"
		)
		(pin "G11"
		)
		(pin "G12"
		)
		(pin "G13"
		)
		(pin "G14"
		)
		(pin "G9"
		)
		(pin "H10"
		)
		(pin "H11"
		)
		(pin "H12"
		)
		(pin "H13"
		)
		(pin "H14"
		)
		(pin "H8"
		)
		(pin "H9"
		)
		(pin "J10"
		)
		(pin "J11"
		)
		(pin "J13"
		)
		(pin "J14"
		)
		(pin "J8"
		)
		(pin "AA14"
		)
		(pin "AA15"
		)
		(pin "AA17"
		)
		(pin "AA18"
		)
		(pin "AA19"
		)
		(pin "AA20"
		)
		(pin "AB14"
		)
		(pin "AB15"
		)
		(pin "AB16"
		)
		(pin "AB17"
		)
		(pin "AB18"
		)
		(pin "AB19"
		)
		(pin "AB20"
		)
		(pin "AC14"
		)
		(pin "AC15"
		)
		(pin "AC16"
		)
		(pin "AC17"
		)
		(pin "AC18"
		)
		(pin "AC19"
		)
		(pin "AD14"
		)
		(pin "AD15"
		)
		(pin "AD16"
		)
		(pin "AD18"
		)
		(pin "AD19"
		)
		(pin "AD20"
		)
		(pin "AE15"
		)
		(pin "AE16"
		)
		(pin "AE17"
		)
		(pin "AE18"
		)
		(pin "AE19"
		)
		(pin "AE20"
		)
		(pin "AF14"
		)
		(pin "AF15"
		)
		(pin "AF16"
		)
		(pin "AF17"
		)
		(pin "AF18"
		)
		(pin "AF19"
		)
		(pin "AF20"
		)
		(pin "V13"
		)
		(pin "V14"
		)
		(pin "V16"
		)
		(pin "V17"
		)
		(pin "V18"
		)
		(pin "V19"
		)
		(pin "W13"
		)
		(pin "W14"
		)
		(pin "W15"
		)
		(pin "W16"
		)
		(pin "W17"
		)
		(pin "W18"
		)
		(pin "W19"
		)
		(pin "Y14"
		)
		(pin "Y15"
		)
		(pin "Y16"
		)
		(pin "Y17"
		)
		(pin "Y18"
		)
		(pin "AA10"
		)
		(pin "AA11"
		)
		(pin "AA12"
		)
		(pin "AA13"
		)
		(pin "AA7"
		)
		(pin "AA8"
		)
		(pin "AA9"
		)
		(pin "AB10"
		)
		(pin "AB11"
		)
		(pin "AB12"
		)
		(pin "AB7"
		)
		(pin "AB8"
		)
		(pin "AB9"
		)
		(pin "AC11"
		)
		(pin "AC12"
		)
		(pin "AC13"
		)
		(pin "AC7"
		)
		(pin "AC8"
		)
		(pin "AC9"
		)
		(pin "AD10"
		)
		(pin "AD11"
		)
		(pin "AD12"
		)
		(pin "AD13"
		)
		(pin "AD8"
		)
		(pin "AD9"
		)
		(pin "AE10"
		)
		(pin "AE11"
		)
		(pin "AE12"
		)
		(pin "AE13"
		)
		(pin "AE7"
		)
		(pin "AE8"
		)
		(pin "AE9"
		)
		(pin "AF10"
		)
		(pin "AF12"
		)
		(pin "AF13"
		)
		(pin "AF7"
		)
		(pin "AF8"
		)
		(pin "AF9"
		)
		(pin "U9"
		)
		(pin "V10"
		)
		(pin "V11"
		)
		(pin "V12"
		)
		(pin "V7"
		)
		(pin "V8"
		)
		(pin "V9"
		)
		(pin "W10"
		)
		(pin "W11"
		)
		(pin "W7"
		)
		(pin "W8"
		)
		(pin "W9"
		)
		(pin "Y10"
		)
		(pin "Y11"
		)
		(pin "Y12"
		)
		(pin "Y13"
		)
		(pin "Y7"
		)
		(pin "Y8"
		)
		(pin "AA1"
		)
		(pin "AA2"
		)
		(pin "AA3"
		)
		(pin "AA4"
		)
		(pin "AA5"
		)
		(pin "AB1"
		)
		(pin "AB2"
		)
		(pin "AB4"
		)
		(pin "AB5"
		)
		(pin "AB6"
		)
		(pin "AC1"
		)
		(pin "AC2"
		)
		(pin "AC3"
		)
		(pin "AC4"
		)
		(pin "AC5"
		)
		(pin "AC6"
		)
		(pin "AD1"
		)
		(pin "AD2"
		)
		(pin "AD3"
		)
		(pin "AD4"
		)
		(pin "AD5"
		)
		(pin "AD6"
		)
		(pin "AE1"
		)
		(pin "AE2"
		)
		(pin "AE3"
		)
		(pin "AE5"
		)
		(pin "AE6"
		)
		(pin "AF2"
		)
		(pin "AF3"
		)
		(pin "AF4"
		)
		(pin "AF5"
		)
		(pin "AF6"
		)
		(pin "T7"
		)
		(pin "U1"
		)
		(pin "U2"
		)
		(pin "U3"
		)
		(pin "U4"
		)
		(pin "U5"
		)
		(pin "U6"
		)
		(pin "U7"
		)
		(pin "V1"
		)
		(pin "V2"
		)
		(pin "V3"
		)
		(pin "V4"
		)
		(pin "V6"
		)
		(pin "W1"
		)
		(pin "W3"
		)
		(pin "W4"
		)
		(pin "W5"
		)
		(pin "W6"
		)
		(pin "Y1"
		)
		(pin "Y2"
		)
		(pin "Y3"
		)
		(pin "Y4"
		)
		(pin "Y5"
		)
		(pin "Y6"
		)
		(pin "A3"
		)
		(pin "A4"
		)
		(pin "B1"
		)
		(pin "B2"
		)
		(pin "B5"
		)
		(pin "B6"
		)
		(pin "C3"
		)
		(pin "C4"
		)
		(pin "D1"
		)
		(pin "D2"
		)
		(pin "D5"
		)
		(pin "D6"
		)
		(pin "E3"
		)
		(pin "E4"
		)
		(pin "F1"
		)
		(pin "F2"
		)
		(pin "F5"
		)
		(pin "F6"
		)
		(pin "G3"
		)
		(pin "G4"
		)
		(pin "H1"
		)
		(pin "H2"
		)
		(pin "H5"
		)
		(pin "H6"
		)
		(pin "J3"
		)
		(pin "J4"
		)
		(pin "K1"
		)
		(pin "K2"
		)
		(pin "K5"
		)
		(pin "K6"
		)
		(pin "L3"
		)
		(pin "L4"
		)
		(pin "M1"
		)
		(pin "M2"
		)
		(pin "N3"
		)
		(pin "N4"
		)
		(pin "P1"
		)
		(pin "P2"
		)
		(pin "R3"
		)
		(pin "R4"
		)
		(pin "A1"
		)
		(pin "A16"
		)
		(pin "A2"
		)
		(pin "A26"
		)
		(pin "A5"
		)
		(pin "A6"
		)
		(pin "A7"
		)
		(pin "AA16"
		)
		(pin "AA26"
		)
		(pin "AA6"
		)
		(pin "AB13"
		)
		(pin "AB23"
		)
		(pin "AB3"
		)
		(pin "AC10"
		)
		(pin "AC20"
		)
		(pin "AD17"
		)
		(pin "AD7"
		)
		(pin "AE14"
		)
		(pin "AE24"
		)
		(pin "AE4"
		)
		(pin "AF1"
		)
		(pin "AF11"
		)
		(pin "AF21"
		)
		(pin "B13"
		)
		(pin "B23"
		)
		(pin "B3"
		)
		(pin "B4"
		)
		(pin "B7"
		)
		(pin "C1"
		)
		(pin "C10"
		)
		(pin "C2"
		)
		(pin "C20"
		)
		(pin "C5"
		)
		(pin "C6"
		)
		(pin "C7"
		)
		(pin "D17"
		)
		(pin "D3"
		)
		(pin "D4"
		)
		(pin "D7"
		)
		(pin "E1"
		)
		(pin "E14"
		)
		(pin "E2"
		)
		(pin "E24"
		)
		(pin "E5"
		)
		(pin "E6"
		)
		(pin "E7"
		)
		(pin "E8"
		)
		(pin "F11"
		)
		(pin "F21"
		)
		(pin "F3"
		)
		(pin "F4"
		)
		(pin "F7"
		)
		(pin "G1"
		)
		(pin "G18"
		)
		(pin "G2"
		)
		(pin "G5"
		)
		(pin "G6"
		)
		(pin "G8"
		)
		(pin "H15"
		)
		(pin "H25"
		)
		(pin "H3"
		)
		(pin "H4"
		)
		(pin "H7"
		)
		(pin "J1"
		)
		(pin "J12"
		)
		(pin "J2"
		)
		(pin "J22"
		)
		(pin "J5"
		)
		(pin "J6"
		)
		(pin "J9"
		)
		(pin "K10"
		)
		(pin "K11"
		)
		(pin "K12"
		)
		(pin "K13"
		)
		(pin "K14"
		)
		(pin "K19"
		)
		(pin "K3"
		)
		(pin "K4"
		)
		(pin "K7"
		)
		(pin "K8"
		)
		(pin "K9"
		)
		(pin "L1"
		)
		(pin "L10"
		)
		(pin "L11"
		)
		(pin "L12"
		)
		(pin "L13"
		)
		(pin "L14"
		)
		(pin "L15"
		)
		(pin "L16"
		)
		(pin "L2"
		)
		(pin "L26"
		)
		(pin "L5"
		)
		(pin "L6"
		)
		(pin "L9"
		)
		(pin "M10"
		)
		(pin "M11"
		)
		(pin "M12"
		)
		(pin "M13"
		)
		(pin "M14"
		)
		(pin "M15"
		)
		(pin "M23"
		)
		(pin "M3"
		)
		(pin "M4"
		)
		(pin "M5"
		)
		(pin "M6"
		)
		(pin "M7"
		)
		(pin "M8"
		)
		(pin "M9"
		)
		(pin "N1"
		)
		(pin "N10"
		)
		(pin "N13"
		)
		(pin "N14"
		)
		(pin "N15"
		)
		(pin "N2"
		)
		(pin "N20"
		)
		(pin "N5"
		)
		(pin "N6"
		)
		(pin "N7"
		)
		(pin "N9"
		)
		(pin "P10"
		)
		(pin "P13"
		)
		(pin "P14"
		)
		(pin "P15"
		)
		(pin "P17"
		)
		(pin "P3"
		)
		(pin "P4"
		)
		(pin "P8"
		)
		(pin "P9"
		)
		(pin "R1"
		)
		(pin "R10"
		)
		(pin "R13"
		)
		(pin "R14"
		)
		(pin "R15"
		)
		(pin "R2"
		)
		(pin "R24"
		)
		(pin "R5"
		)
		(pin "R8"
		)
		(pin "R9"
		)
		(pin "T1"
		)
		(pin "T10"
		)
		(pin "T11"
		)
		(pin "T12"
		)
		(pin "T13"
		)
		(pin "T14"
		)
		(pin "T15"
		)
		(pin "T21"
		)
		(pin "T3"
		)
		(pin "T4"
		)
		(pin "T8"
		)
		(pin "T9"
		)
		(pin "U10"
		)
		(pin "U11"
		)
		(pin "U12"
		)
		(pin "U13"
		)
		(pin "U14"
		)
		(pin "U15"
		)
		(pin "U18"
		)
		(pin "U8"
		)
		(pin "V15"
		)
		(pin "V25"
		)
		(pin "V5"
		)
		(pin "W12"
		)
		(pin "W2"
		)
		(pin "W22"
		)
		(pin "Y19"
		)
		(pin "Y9"
		)
		(pin "C8"
		)
		(pin "G7"
		)
		(pin "J7"
		)
		(pin "L7"
		)
		(pin "L8"
		)
		(pin "N11"
		)
		(pin "N12"
		)
		(pin "N8"
		)
		(pin "P11"
		)
		(pin "P12"
		)
		(pin "P5"
		)
		(pin "P6"
		)
		(pin "P7"
		)
		(pin "R11"
		)
		(pin "R12"
		)
		(pin "R6"
		)
		(pin "R7"
		)
		(pin "T2"
		)
		(pin "T5"
		)
		(pin "T6"
		)
		(instances
			(project "sodimm-ddr5-tester"
				(path ""
					(reference "U4")
					(unit 7)
				)
			)
		)
	)
	(symbol
		(lib_id "antmicroResistors0402:R_0R_0402")
		(at 66.04 245.745 0)
		(unit 1)
		(exclude_from_sim no)
		(in_bom no)
		(on_board yes)
		(dnp yes)
		(property "Reference" "R132"
			(at 68.58 241.171 0)
			(effects
				(font
					(size 1.27 1.27)
					(thickness 0.15)
				)
			)
		)
		(property "Value" "R_0R_0402"
			(at 86.36 258.445 0)
			(effects
				(font
					(size 1.27 1.27)
					(thickness 0.15)
				)
				(justify left bottom)
				(hide yes)
			)
		)
		(property "Footprint" "antmicro-footprints:R_0402_1005Metric"
			(at 86.36 260.985 0)
			(effects
				(font
					(size 1.27 1.27)
					(thickness 0.15)
				)
				(justify left bottom)
				(hide yes)
			)
		)
		(property "Datasheet" "https://industrial.panasonic.com/cdbs/www-data/pdf/RDA0000/AOA0000C301.pdf"
			(at 86.36 263.525 0)
			(effects
				(font
					(size 1.27 1.27)
					(thickness 0.15)
				)
				(justify left bottom)
				(hide yes)
			)
		)
		(property "Description" ""
			(at 66.04 245.745 0)
			(effects
				(font
					(size 1.27 1.27)
				)
			)
		)
		(property "MPN" "ERJ2GE0R00X"
			(at 86.36 266.065 0)
			(effects
				(font
					(size 1.27 1.27)
					(thickness 0.15)
				)
				(justify left bottom)
				(hide yes)
			)
		)
		(property "Manufacturer" "Panasonic"
			(at 86.36 268.605 0)
			(effects
				(font
					(size 1.27 1.27)
					(thickness 0.15)
				)
				(justify left bottom)
				(hide yes)
			)
		)
		(property "License" "Apache-2.0"
			(at 86.36 271.145 0)
			(effects
				(font
					(size 1.27 1.27)
					(thickness 0.15)
				)
				(justify left bottom)
				(hide yes)
			)
		)
		(property "Author" "Antmicro"
			(at 86.36 273.685 0)
			(effects
				(font
					(size 1.27 1.27)
					(thickness 0.15)
				)
				(justify left bottom)
				(hide yes)
			)
		)
		(property "Val" "0R"
			(at 68.58 243.6947 0)
			(effects
				(font
					(size 1.27 1.27)
					(thickness 0.15)
				)
			)
		)
		(property "Tolerance" "~"
			(at 86.36 255.905 0)
			(effects
				(font
					(size 1.27 1.27)
				)
				(justify left bottom)
				(hide yes)
			)
		)
		(property "Current" "1A"
			(at 86.36 276.225 0)
			(effects
				(font
					(size 1.27 1.27)
					(thickness 0.15)
				)
				(justify left bottom)
				(hide yes)
			)
		)
		(pin "1"
		)
		(pin "2"
		)
		(instances
			(project "sodimm-ddr5-tester"
				(path ""
					(reference "R132")
					(unit 1)
				)
			)
		)
	)
	(symbol
		(lib_id "antmicroResistors0402:R_0R_0402")
		(at 66.04 238.125 0)
		(unit 1)
		(exclude_from_sim no)
		(in_bom no)
		(on_board yes)
		(dnp no)
		(property "Reference" "R131"
			(at 68.58 233.551 0)
			(effects
				(font
					(size 1.27 1.27)
					(thickness 0.15)
				)
			)
		)
		(property "Value" "R_0R_0402"
			(at 86.36 250.825 0)
			(effects
				(font
					(size 1.27 1.27)
					(thickness 0.15)
				)
				(justify left bottom)
				(hide yes)
			)
		)
		(property "Footprint" "antmicro-footprints:R_0402_1005Metric"
			(at 86.36 253.365 0)
			(effects
				(font
					(size 1.27 1.27)
					(thickness 0.15)
				)
				(justify left bottom)
				(hide yes)
			)
		)
		(property "Datasheet" "https://industrial.panasonic.com/cdbs/www-data/pdf/RDA0000/AOA0000C301.pdf"
			(at 86.36 255.905 0)
			(effects
				(font
					(size 1.27 1.27)
					(thickness 0.15)
				)
				(justify left bottom)
				(hide yes)
			)
		)
		(property "Description" ""
			(at 66.04 238.125 0)
			(effects
				(font
					(size 1.27 1.27)
				)
			)
		)
		(property "MPN" "ERJ2GE0R00X"
			(at 86.36 258.445 0)
			(effects
				(font
					(size 1.27 1.27)
					(thickness 0.15)
				)
				(justify left bottom)
				(hide yes)
			)
		)
		(property "Manufacturer" "Panasonic"
			(at 86.36 260.985 0)
			(effects
				(font
					(size 1.27 1.27)
					(thickness 0.15)
				)
				(justify left bottom)
				(hide yes)
			)
		)
		(property "License" "Apache-2.0"
			(at 86.36 263.525 0)
			(effects
				(font
					(size 1.27 1.27)
					(thickness 0.15)
				)
				(justify left bottom)
				(hide yes)
			)
		)
		(property "Author" "Antmicro"
			(at 86.36 266.065 0)
			(effects
				(font
					(size 1.27 1.27)
					(thickness 0.15)
				)
				(justify left bottom)
				(hide yes)
			)
		)
		(property "Val" "0R"
			(at 68.58 236.0747 0)
			(effects
				(font
					(size 1.27 1.27)
					(thickness 0.15)
				)
			)
		)
		(property "Tolerance" "~"
			(at 86.36 248.285 0)
			(effects
				(font
					(size 1.27 1.27)
				)
				(justify left bottom)
				(hide yes)
			)
		)
		(property "Current" "1A"
			(at 86.36 268.605 0)
			(effects
				(font
					(size 1.27 1.27)
					(thickness 0.15)
				)
				(justify left bottom)
				(hide yes)
			)
		)
		(pin "1"
		)
		(pin "2"
		)
		(instances
			(project "sodimm-ddr5-tester"
				(path ""
					(reference "R131")
					(unit 1)
				)
			)
		)
	)
	(symbol
		(lib_id "antmicropower:+1V1")
		(at 34.29 236.855 0)
		(unit 1)
		(exclude_from_sim no)
		(in_bom yes)
		(on_board yes)
		(dnp no)
		(fields_autoplaced yes)
		(property "Reference" "#PWR0276"
			(at 34.29 240.665 0)
			(effects
				(font
					(size 1.27 1.27)
				)
				(hide yes)
			)
		)
		(property "Value" "+1V1"
			(at 34.29 233.299 0)
			(effects
				(font
					(size 1.27 1.27)
				)
			)
		)
		(property "Footprint" ""
			(at 34.29 236.855 0)
			(effects
				(font
					(size 1.27 1.27)
				)
				(hide yes)
			)
		)
		(property "Datasheet" ""
			(at 34.29 236.855 0)
			(effects
				(font
					(size 1.27 1.27)
				)
				(hide yes)
			)
		)
		(property "Description" ""
			(at 34.29 236.855 0)
			(effects
				(font
					(size 1.27 1.27)
				)
			)
		)
		(pin "1"
		)
		(instances
			(project "sodimm-ddr5-tester"
				(path ""
					(reference "#PWR0276")
					(unit 1)
				)
			)
		)
	)
	(symbol
		(lib_id "antmicroResistors0402:R_1k_0402")
		(at 34.29 253.365 90)
		(unit 1)
		(exclude_from_sim no)
		(in_bom yes)
		(on_board yes)
		(dnp no)
		(fields_autoplaced yes)
		(property "Reference" "R130"
			(at 35.941 249.9944 90)
			(effects
				(font
					(size 1.27 1.27)
					(thickness 0.15)
				)
				(justify right)
			)
		)
		(property "Value" "R_1k_0402"
			(at 46.99 233.045 0)
			(effects
				(font
					(size 1.27 1.27)
					(thickness 0.15)
				)
				(justify left bottom)
				(hide yes)
			)
		)
		(property "Footprint" "antmicro-footprints:R_0402_1005Metric"
			(at 49.53 233.045 0)
			(effects
				(font
					(size 1.27 1.27)
					(thickness 0.15)
				)
				(justify left bottom)
				(hide yes)
			)
		)
		(property "Datasheet" "https://www.bourns.com/docs/product-datasheets/cr.pdf"
			(at 52.07 233.045 0)
			(effects
				(font
					(size 1.27 1.27)
					(thickness 0.15)
				)
				(justify left bottom)
				(hide yes)
			)
		)
		(property "Description" ""
			(at 34.29 253.365 0)
			(effects
				(font
					(size 1.27 1.27)
				)
			)
		)
		(property "MPN" "CR0402-FX-1001GLF"
			(at 54.61 233.045 0)
			(effects
				(font
					(size 1.27 1.27)
					(thickness 0.15)
				)
				(justify left bottom)
				(hide yes)
			)
		)
		(property "Manufacturer" "Bourns"
			(at 57.15 233.045 0)
			(effects
				(font
					(size 1.27 1.27)
					(thickness 0.15)
				)
				(justify left bottom)
				(hide yes)
			)
		)
		(property "License" "Apache-2.0"
			(at 59.69 233.045 0)
			(effects
				(font
					(size 1.27 1.27)
					(thickness 0.15)
				)
				(justify left bottom)
				(hide yes)
			)
		)
		(property "Author" "Antmicro"
			(at 62.23 233.045 0)
			(effects
				(font
					(size 1.27 1.27)
					(thickness 0.15)
				)
				(justify left bottom)
				(hide yes)
			)
		)
		(property "Val" "1k"
			(at 35.941 252.5181 90)
			(effects
				(font
					(size 1.27 1.27)
					(thickness 0.15)
				)
				(justify right)
			)
		)
		(property "Tolerance" "1%"
			(at 44.45 233.045 0)
			(effects
				(font
					(size 1.27 1.27)
				)
				(justify left bottom)
				(hide yes)
			)
		)
		(pin "1"
		)
		(pin "2"
		)
		(instances
			(project "sodimm-ddr5-tester"
				(path ""
					(reference "R130")
					(unit 1)
				)
			)
		)
	)
	(symbol
		(lib_id "antmicroFPGAChips:XC7K160T-FFG676")
		(at 317.5 59.69 0)
		(unit 8)
		(exclude_from_sim no)
		(in_bom yes)
		(on_board yes)
		(dnp no)
		(fields_autoplaced yes)
		(property "Reference" "U4"
			(at 351.282 123.6294 0)
			(effects
				(font
					(size 1.27 1.27)
				)
				(justify left)
			)
		)
		(property "Value" "XC7K160T-FFG676"
			(at 351.282 126.1597 0)
			(effects
				(font
					(size 1.27 1.27)
					(thickness 0.15)
				)
				(justify left)
			)
		)
		(property "Footprint" "antmicro-footprints:BGA-676_27x27mm_Layout26x26_P1x1mm_FFG676"
			(at 386.08 62.23 0)
			(effects
				(font
					(size 1.27 1.27)
					(thickness 0.15)
				)
				(justify left bottom)
				(hide yes)
			)
		)
		(property "Datasheet" "https://docs.xilinx.com/v/u/en-US/ds180_7Series_Overview"
			(at 386.08 64.77 0)
			(effects
				(font
					(size 1.27 1.27)
					(thickness 0.15)
				)
				(justify left bottom)
				(hide yes)
			)
		)
		(property "Description" ""
			(at 317.5 59.69 0)
			(effects
				(font
					(size 1.27 1.27)
				)
			)
		)
		(property "MPN" "XC7K160T-FFG676"
			(at 317.5 59.69 0)
			(effects
				(font
					(size 1.27 1.27)
				)
				(hide yes)
			)
		)
		(property "Author" "Antmicro"
			(at 386.08 67.31 0)
			(effects
				(font
					(size 1.27 1.27)
					(thickness 0.15)
				)
				(justify left bottom)
				(hide yes)
			)
		)
		(property "License" "Apache-2.0"
			(at 386.08 69.85 0)
			(effects
				(font
					(size 1.27 1.27)
					(thickness 0.15)
				)
				(justify left bottom)
				(hide yes)
			)
		)
		(property "Manufacturer" "AMD-Xilinx"
			(at 317.5 59.69 0)
			(effects
				(font
					(size 1.27 1.27)
				)
				(hide yes)
			)
		)
		(pin "AA21"
		)
		(pin "AA22"
		)
		(pin "AA23"
		)
		(pin "AA24"
		)
		(pin "AA25"
		)
		(pin "AB21"
		)
		(pin "AB22"
		)
		(pin "AB24"
		)
		(pin "AB25"
		)
		(pin "AB26"
		)
		(pin "AC21"
		)
		(pin "AC22"
		)
		(pin "AC23"
		)
		(pin "AC24"
		)
		(pin "AC25"
		)
		(pin "AC26"
		)
		(pin "AD21"
		)
		(pin "AD22"
		)
		(pin "AD23"
		)
		(pin "AD24"
		)
		(pin "AD25"
		)
		(pin "AD26"
		)
		(pin "AE21"
		)
		(pin "AE22"
		)
		(pin "AE23"
		)
		(pin "AE25"
		)
		(pin "AE26"
		)
		(pin "AF22"
		)
		(pin "AF23"
		)
		(pin "AF24"
		)
		(pin "AF25"
		)
		(pin "AF26"
		)
		(pin "U21"
		)
		(pin "U22"
		)
		(pin "U23"
		)
		(pin "U24"
		)
		(pin "U25"
		)
		(pin "U26"
		)
		(pin "V20"
		)
		(pin "V21"
		)
		(pin "V22"
		)
		(pin "V23"
		)
		(pin "V24"
		)
		(pin "V26"
		)
		(pin "W20"
		)
		(pin "W21"
		)
		(pin "W23"
		)
		(pin "W24"
		)
		(pin "W25"
		)
		(pin "W26"
		)
		(pin "Y20"
		)
		(pin "Y21"
		)
		(pin "Y22"
		)
		(pin "Y23"
		)
		(pin "Y24"
		)
		(pin "Y25"
		)
		(pin "Y26"
		)
		(pin "K24"
		)
		(pin "K25"
		)
		(pin "K26"
		)
		(pin "L24"
		)
		(pin "L25"
		)
		(pin "M19"
		)
		(pin "M20"
		)
		(pin "M21"
		)
		(pin "M22"
		)
		(pin "M24"
		)
		(pin "M25"
		)
		(pin "M26"
		)
		(pin "N16"
		)
		(pin "N17"
		)
		(pin "N18"
		)
		(pin "N19"
		)
		(pin "N21"
		)
		(pin "N22"
		)
		(pin "N23"
		)
		(pin "N24"
		)
		(pin "N25"
		)
		(pin "N26"
		)
		(pin "P16"
		)
		(pin "P18"
		)
		(pin "P19"
		)
		(pin "P20"
		)
		(pin "P21"
		)
		(pin "P22"
		)
		(pin "P23"
		)
		(pin "P24"
		)
		(pin "P25"
		)
		(pin "P26"
		)
		(pin "R16"
		)
		(pin "R17"
		)
		(pin "R18"
		)
		(pin "R19"
		)
		(pin "R20"
		)
		(pin "R21"
		)
		(pin "R22"
		)
		(pin "R23"
		)
		(pin "R25"
		)
		(pin "R26"
		)
		(pin "T16"
		)
		(pin "T17"
		)
		(pin "T18"
		)
		(pin "T19"
		)
		(pin "T20"
		)
		(pin "T22"
		)
		(pin "T23"
		)
		(pin "T24"
		)
		(pin "T25"
		)
		(pin "T26"
		)
		(pin "U16"
		)
		(pin "U17"
		)
		(pin "U19"
		)
		(pin "U20"
		)
		(pin "A20"
		)
		(pin "A21"
		)
		(pin "A22"
		)
		(pin "A23"
		)
		(pin "A24"
		)
		(pin "A25"
		)
		(pin "B20"
		)
		(pin "B21"
		)
		(pin "B22"
		)
		(pin "B24"
		)
		(pin "B25"
		)
		(pin "B26"
		)
		(pin "C21"
		)
		(pin "C22"
		)
		(pin "C23"
		)
		(pin "C24"
		)
		(pin "C25"
		)
		(pin "C26"
		)
		(pin "D21"
		)
		(pin "D22"
		)
		(pin "D23"
		)
		(pin "D24"
		)
		(pin "D25"
		)
		(pin "D26"
		)
		(pin "E21"
		)
		(pin "E22"
		)
		(pin "E23"
		)
		(pin "E25"
		)
		(pin "E26"
		)
		(pin "F22"
		)
		(pin "F23"
		)
		(pin "F24"
		)
		(pin "F25"
		)
		(pin "F26"
		)
		(pin "G21"
		)
		(pin "G22"
		)
		(pin "G23"
		)
		(pin "G24"
		)
		(pin "G25"
		)
		(pin "G26"
		)
		(pin "H21"
		)
		(pin "H22"
		)
		(pin "H23"
		)
		(pin "H24"
		)
		(pin "H26"
		)
		(pin "J21"
		)
		(pin "J23"
		)
		(pin "J24"
		)
		(pin "J25"
		)
		(pin "J26"
		)
		(pin "K21"
		)
		(pin "K22"
		)
		(pin "K23"
		)
		(pin "L21"
		)
		(pin "L22"
		)
		(pin "L23"
		)
		(pin "A17"
		)
		(pin "A18"
		)
		(pin "A19"
		)
		(pin "B16"
		)
		(pin "B17"
		)
		(pin "B18"
		)
		(pin "B19"
		)
		(pin "C16"
		)
		(pin "C17"
		)
		(pin "C18"
		)
		(pin "C19"
		)
		(pin "D15"
		)
		(pin "D16"
		)
		(pin "D18"
		)
		(pin "D19"
		)
		(pin "D20"
		)
		(pin "E15"
		)
		(pin "E16"
		)
		(pin "E17"
		)
		(pin "E18"
		)
		(pin "E19"
		)
		(pin "E20"
		)
		(pin "F15"
		)
		(pin "F16"
		)
		(pin "F17"
		)
		(pin "F18"
		)
		(pin "F19"
		)
		(pin "F20"
		)
		(pin "G15"
		)
		(pin "G16"
		)
		(pin "G17"
		)
		(pin "G19"
		)
		(pin "G20"
		)
		(pin "H16"
		)
		(pin "H17"
		)
		(pin "H18"
		)
		(pin "H19"
		)
		(pin "H20"
		)
		(pin "J15"
		)
		(pin "J16"
		)
		(pin "J17"
		)
		(pin "J18"
		)
		(pin "J19"
		)
		(pin "J20"
		)
		(pin "K15"
		)
		(pin "K16"
		)
		(pin "K17"
		)
		(pin "K18"
		)
		(pin "K20"
		)
		(pin "L17"
		)
		(pin "L18"
		)
		(pin "L19"
		)
		(pin "L20"
		)
		(pin "M16"
		)
		(pin "M17"
		)
		(pin "M18"
		)
		(pin "A10"
		)
		(pin "A11"
		)
		(pin "A12"
		)
		(pin "A13"
		)
		(pin "A14"
		)
		(pin "A15"
		)
		(pin "A8"
		)
		(pin "A9"
		)
		(pin "B10"
		)
		(pin "B11"
		)
		(pin "B12"
		)
		(pin "B14"
		)
		(pin "B15"
		)
		(pin "B8"
		)
		(pin "B9"
		)
		(pin "C11"
		)
		(pin "C12"
		)
		(pin "C13"
		)
		(pin "C14"
		)
		(pin "C15"
		)
		(pin "C9"
		)
		(pin "D10"
		)
		(pin "D11"
		)
		(pin "D12"
		)
		(pin "D13"
		)
		(pin "D14"
		)
		(pin "D8"
		)
		(pin "D9"
		)
		(pin "E10"
		)
		(pin "E11"
		)
		(pin "E12"
		)
		(pin "E13"
		)
		(pin "E9"
		)
		(pin "F10"
		)
		(pin "F12"
		)
		(pin "F13"
		)
		(pin "F14"
		)
		(pin "F8"
		)
		(pin "F9"
		)
		(pin "G10"
		)
		(pin "G11"
		)
		(pin "G12"
		)
		(pin "G13"
		)
		(pin "G14"
		)
		(pin "G9"
		)
		(pin "H10"
		)
		(pin "H11"
		)
		(pin "H12"
		)
		(pin "H13"
		)
		(pin "H14"
		)
		(pin "H8"
		)
		(pin "H9"
		)
		(pin "J10"
		)
		(pin "J11"
		)
		(pin "J13"
		)
		(pin "J14"
		)
		(pin "J8"
		)
		(pin "AA14"
		)
		(pin "AA15"
		)
		(pin "AA17"
		)
		(pin "AA18"
		)
		(pin "AA19"
		)
		(pin "AA20"
		)
		(pin "AB14"
		)
		(pin "AB15"
		)
		(pin "AB16"
		)
		(pin "AB17"
		)
		(pin "AB18"
		)
		(pin "AB19"
		)
		(pin "AB20"
		)
		(pin "AC14"
		)
		(pin "AC15"
		)
		(pin "AC16"
		)
		(pin "AC17"
		)
		(pin "AC18"
		)
		(pin "AC19"
		)
		(pin "AD14"
		)
		(pin "AD15"
		)
		(pin "AD16"
		)
		(pin "AD18"
		)
		(pin "AD19"
		)
		(pin "AD20"
		)
		(pin "AE15"
		)
		(pin "AE16"
		)
		(pin "AE17"
		)
		(pin "AE18"
		)
		(pin "AE19"
		)
		(pin "AE20"
		)
		(pin "AF14"
		)
		(pin "AF15"
		)
		(pin "AF16"
		)
		(pin "AF17"
		)
		(pin "AF18"
		)
		(pin "AF19"
		)
		(pin "AF20"
		)
		(pin "V13"
		)
		(pin "V14"
		)
		(pin "V16"
		)
		(pin "V17"
		)
		(pin "V18"
		)
		(pin "V19"
		)
		(pin "W13"
		)
		(pin "W14"
		)
		(pin "W15"
		)
		(pin "W16"
		)
		(pin "W17"
		)
		(pin "W18"
		)
		(pin "W19"
		)
		(pin "Y14"
		)
		(pin "Y15"
		)
		(pin "Y16"
		)
		(pin "Y17"
		)
		(pin "Y18"
		)
		(pin "AA10"
		)
		(pin "AA11"
		)
		(pin "AA12"
		)
		(pin "AA13"
		)
		(pin "AA7"
		)
		(pin "AA8"
		)
		(pin "AA9"
		)
		(pin "AB10"
		)
		(pin "AB11"
		)
		(pin "AB12"
		)
		(pin "AB7"
		)
		(pin "AB8"
		)
		(pin "AB9"
		)
		(pin "AC11"
		)
		(pin "AC12"
		)
		(pin "AC13"
		)
		(pin "AC7"
		)
		(pin "AC8"
		)
		(pin "AC9"
		)
		(pin "AD10"
		)
		(pin "AD11"
		)
		(pin "AD12"
		)
		(pin "AD13"
		)
		(pin "AD8"
		)
		(pin "AD9"
		)
		(pin "AE10"
		)
		(pin "AE11"
		)
		(pin "AE12"
		)
		(pin "AE13"
		)
		(pin "AE7"
		)
		(pin "AE8"
		)
		(pin "AE9"
		)
		(pin "AF10"
		)
		(pin "AF12"
		)
		(pin "AF13"
		)
		(pin "AF7"
		)
		(pin "AF8"
		)
		(pin "AF9"
		)
		(pin "U9"
		)
		(pin "V10"
		)
		(pin "V11"
		)
		(pin "V12"
		)
		(pin "V7"
		)
		(pin "V8"
		)
		(pin "V9"
		)
		(pin "W10"
		)
		(pin "W11"
		)
		(pin "W7"
		)
		(pin "W8"
		)
		(pin "W9"
		)
		(pin "Y10"
		)
		(pin "Y11"
		)
		(pin "Y12"
		)
		(pin "Y13"
		)
		(pin "Y7"
		)
		(pin "Y8"
		)
		(pin "AA1"
		)
		(pin "AA2"
		)
		(pin "AA3"
		)
		(pin "AA4"
		)
		(pin "AA5"
		)
		(pin "AB1"
		)
		(pin "AB2"
		)
		(pin "AB4"
		)
		(pin "AB5"
		)
		(pin "AB6"
		)
		(pin "AC1"
		)
		(pin "AC2"
		)
		(pin "AC3"
		)
		(pin "AC4"
		)
		(pin "AC5"
		)
		(pin "AC6"
		)
		(pin "AD1"
		)
		(pin "AD2"
		)
		(pin "AD3"
		)
		(pin "AD4"
		)
		(pin "AD5"
		)
		(pin "AD6"
		)
		(pin "AE1"
		)
		(pin "AE2"
		)
		(pin "AE3"
		)
		(pin "AE5"
		)
		(pin "AE6"
		)
		(pin "AF2"
		)
		(pin "AF3"
		)
		(pin "AF4"
		)
		(pin "AF5"
		)
		(pin "AF6"
		)
		(pin "T7"
		)
		(pin "U1"
		)
		(pin "U2"
		)
		(pin "U3"
		)
		(pin "U4"
		)
		(pin "U5"
		)
		(pin "U6"
		)
		(pin "U7"
		)
		(pin "V1"
		)
		(pin "V2"
		)
		(pin "V3"
		)
		(pin "V4"
		)
		(pin "V6"
		)
		(pin "W1"
		)
		(pin "W3"
		)
		(pin "W4"
		)
		(pin "W5"
		)
		(pin "W6"
		)
		(pin "Y1"
		)
		(pin "Y2"
		)
		(pin "Y3"
		)
		(pin "Y4"
		)
		(pin "Y5"
		)
		(pin "Y6"
		)
		(pin "A3"
		)
		(pin "A4"
		)
		(pin "B1"
		)
		(pin "B2"
		)
		(pin "B5"
		)
		(pin "B6"
		)
		(pin "C3"
		)
		(pin "C4"
		)
		(pin "D1"
		)
		(pin "D2"
		)
		(pin "D5"
		)
		(pin "D6"
		)
		(pin "E3"
		)
		(pin "E4"
		)
		(pin "F1"
		)
		(pin "F2"
		)
		(pin "F5"
		)
		(pin "F6"
		)
		(pin "G3"
		)
		(pin "G4"
		)
		(pin "H1"
		)
		(pin "H2"
		)
		(pin "H5"
		)
		(pin "H6"
		)
		(pin "J3"
		)
		(pin "J4"
		)
		(pin "K1"
		)
		(pin "K2"
		)
		(pin "K5"
		)
		(pin "K6"
		)
		(pin "L3"
		)
		(pin "L4"
		)
		(pin "M1"
		)
		(pin "M2"
		)
		(pin "N3"
		)
		(pin "N4"
		)
		(pin "P1"
		)
		(pin "P2"
		)
		(pin "R3"
		)
		(pin "R4"
		)
		(pin "A1"
		)
		(pin "A16"
		)
		(pin "A2"
		)
		(pin "A26"
		)
		(pin "A5"
		)
		(pin "A6"
		)
		(pin "A7"
		)
		(pin "AA16"
		)
		(pin "AA26"
		)
		(pin "AA6"
		)
		(pin "AB13"
		)
		(pin "AB23"
		)
		(pin "AB3"
		)
		(pin "AC10"
		)
		(pin "AC20"
		)
		(pin "AD17"
		)
		(pin "AD7"
		)
		(pin "AE14"
		)
		(pin "AE24"
		)
		(pin "AE4"
		)
		(pin "AF1"
		)
		(pin "AF11"
		)
		(pin "AF21"
		)
		(pin "B13"
		)
		(pin "B23"
		)
		(pin "B3"
		)
		(pin "B4"
		)
		(pin "B7"
		)
		(pin "C1"
		)
		(pin "C10"
		)
		(pin "C2"
		)
		(pin "C20"
		)
		(pin "C5"
		)
		(pin "C6"
		)
		(pin "C7"
		)
		(pin "D17"
		)
		(pin "D3"
		)
		(pin "D4"
		)
		(pin "D7"
		)
		(pin "E1"
		)
		(pin "E14"
		)
		(pin "E2"
		)
		(pin "E24"
		)
		(pin "E5"
		)
		(pin "E6"
		)
		(pin "E7"
		)
		(pin "E8"
		)
		(pin "F11"
		)
		(pin "F21"
		)
		(pin "F3"
		)
		(pin "F4"
		)
		(pin "F7"
		)
		(pin "G1"
		)
		(pin "G18"
		)
		(pin "G2"
		)
		(pin "G5"
		)
		(pin "G6"
		)
		(pin "G8"
		)
		(pin "H15"
		)
		(pin "H25"
		)
		(pin "H3"
		)
		(pin "H4"
		)
		(pin "H7"
		)
		(pin "J1"
		)
		(pin "J12"
		)
		(pin "J2"
		)
		(pin "J22"
		)
		(pin "J5"
		)
		(pin "J6"
		)
		(pin "J9"
		)
		(pin "K10"
		)
		(pin "K11"
		)
		(pin "K12"
		)
		(pin "K13"
		)
		(pin "K14"
		)
		(pin "K19"
		)
		(pin "K3"
		)
		(pin "K4"
		)
		(pin "K7"
		)
		(pin "K8"
		)
		(pin "K9"
		)
		(pin "L1"
		)
		(pin "L10"
		)
		(pin "L11"
		)
		(pin "L12"
		)
		(pin "L13"
		)
		(pin "L14"
		)
		(pin "L15"
		)
		(pin "L16"
		)
		(pin "L2"
		)
		(pin "L26"
		)
		(pin "L5"
		)
		(pin "L6"
		)
		(pin "L9"
		)
		(pin "M10"
		)
		(pin "M11"
		)
		(pin "M12"
		)
		(pin "M13"
		)
		(pin "M14"
		)
		(pin "M15"
		)
		(pin "M23"
		)
		(pin "M3"
		)
		(pin "M4"
		)
		(pin "M5"
		)
		(pin "M6"
		)
		(pin "M7"
		)
		(pin "M8"
		)
		(pin "M9"
		)
		(pin "N1"
		)
		(pin "N10"
		)
		(pin "N13"
		)
		(pin "N14"
		)
		(pin "N15"
		)
		(pin "N2"
		)
		(pin "N20"
		)
		(pin "N5"
		)
		(pin "N6"
		)
		(pin "N7"
		)
		(pin "N9"
		)
		(pin "P10"
		)
		(pin "P13"
		)
		(pin "P14"
		)
		(pin "P15"
		)
		(pin "P17"
		)
		(pin "P3"
		)
		(pin "P4"
		)
		(pin "P8"
		)
		(pin "P9"
		)
		(pin "R1"
		)
		(pin "R10"
		)
		(pin "R13"
		)
		(pin "R14"
		)
		(pin "R15"
		)
		(pin "R2"
		)
		(pin "R24"
		)
		(pin "R5"
		)
		(pin "R8"
		)
		(pin "R9"
		)
		(pin "T1"
		)
		(pin "T10"
		)
		(pin "T11"
		)
		(pin "T12"
		)
		(pin "T13"
		)
		(pin "T14"
		)
		(pin "T15"
		)
		(pin "T21"
		)
		(pin "T3"
		)
		(pin "T4"
		)
		(pin "T8"
		)
		(pin "T9"
		)
		(pin "U10"
		)
		(pin "U11"
		)
		(pin "U12"
		)
		(pin "U13"
		)
		(pin "U14"
		)
		(pin "U15"
		)
		(pin "U18"
		)
		(pin "U8"
		)
		(pin "V15"
		)
		(pin "V25"
		)
		(pin "V5"
		)
		(pin "W12"
		)
		(pin "W2"
		)
		(pin "W22"
		)
		(pin "Y19"
		)
		(pin "Y9"
		)
		(pin "C8"
		)
		(pin "G7"
		)
		(pin "J7"
		)
		(pin "L7"
		)
		(pin "L8"
		)
		(pin "N11"
		)
		(pin "N12"
		)
		(pin "N8"
		)
		(pin "P11"
		)
		(pin "P12"
		)
		(pin "P5"
		)
		(pin "P6"
		)
		(pin "P7"
		)
		(pin "R11"
		)
		(pin "R12"
		)
		(pin "R6"
		)
		(pin "R7"
		)
		(pin "T2"
		)
		(pin "T5"
		)
		(pin "T6"
		)
		(instances
			(project "sodimm-ddr5-tester"
				(path ""
					(reference "U4")
					(unit 8)
				)
			)
		)
	)
	(symbol
		(lib_id "antmicroResistors0402:R_1k_0402")
		(at 34.29 243.205 90)
		(unit 1)
		(exclude_from_sim no)
		(in_bom yes)
		(on_board yes)
		(dnp no)
		(fields_autoplaced yes)
		(property "Reference" "R129"
			(at 35.941 239.8344 90)
			(effects
				(font
					(size 1.27 1.27)
					(thickness 0.15)
				)
				(justify right)
			)
		)
		(property "Value" "R_1k_0402"
			(at 46.99 222.885 0)
			(effects
				(font
					(size 1.27 1.27)
					(thickness 0.15)
				)
				(justify left bottom)
				(hide yes)
			)
		)
		(property "Footprint" "antmicro-footprints:R_0402_1005Metric"
			(at 49.53 222.885 0)
			(effects
				(font
					(size 1.27 1.27)
					(thickness 0.15)
				)
				(justify left bottom)
				(hide yes)
			)
		)
		(property "Datasheet" "https://www.bourns.com/docs/product-datasheets/cr.pdf"
			(at 52.07 222.885 0)
			(effects
				(font
					(size 1.27 1.27)
					(thickness 0.15)
				)
				(justify left bottom)
				(hide yes)
			)
		)
		(property "Description" ""
			(at 34.29 243.205 0)
			(effects
				(font
					(size 1.27 1.27)
				)
			)
		)
		(property "MPN" "CR0402-FX-1001GLF"
			(at 54.61 222.885 0)
			(effects
				(font
					(size 1.27 1.27)
					(thickness 0.15)
				)
				(justify left bottom)
				(hide yes)
			)
		)
		(property "Manufacturer" "Bourns"
			(at 57.15 222.885 0)
			(effects
				(font
					(size 1.27 1.27)
					(thickness 0.15)
				)
				(justify left bottom)
				(hide yes)
			)
		)
		(property "License" "Apache-2.0"
			(at 59.69 222.885 0)
			(effects
				(font
					(size 1.27 1.27)
					(thickness 0.15)
				)
				(justify left bottom)
				(hide yes)
			)
		)
		(property "Author" "Antmicro"
			(at 62.23 222.885 0)
			(effects
				(font
					(size 1.27 1.27)
					(thickness 0.15)
				)
				(justify left bottom)
				(hide yes)
			)
		)
		(property "Val" "1k"
			(at 35.941 242.3581 90)
			(effects
				(font
					(size 1.27 1.27)
					(thickness 0.15)
				)
				(justify right)
			)
		)
		(property "Tolerance" "1%"
			(at 44.45 222.885 0)
			(effects
				(font
					(size 1.27 1.27)
				)
				(justify left bottom)
				(hide yes)
			)
		)
		(pin "1"
		)
		(pin "2"
		)
		(instances
			(project "sodimm-ddr5-tester"
				(path ""
					(reference "R129")
					(unit 1)
				)
			)
		)
	)
	(symbol
		(lib_id "antmicropower:+1V1")
		(at 85.725 58.42 0)
		(unit 1)
		(exclude_from_sim no)
		(in_bom yes)
		(on_board yes)
		(dnp no)
		(fields_autoplaced yes)
		(property "Reference" "#PWR0266"
			(at 85.725 62.23 0)
			(effects
				(font
					(size 1.27 1.27)
				)
				(hide yes)
			)
		)
		(property "Value" "+1V1"
			(at 85.725 54.864 0)
			(effects
				(font
					(size 1.27 1.27)
				)
			)
		)
		(property "Footprint" ""
			(at 85.725 58.42 0)
			(effects
				(font
					(size 1.27 1.27)
				)
				(hide yes)
			)
		)
		(property "Datasheet" ""
			(at 85.725 58.42 0)
			(effects
				(font
					(size 1.27 1.27)
				)
				(hide yes)
			)
		)
		(property "Description" ""
			(at 85.725 58.42 0)
			(effects
				(font
					(size 1.27 1.27)
				)
			)
		)
		(pin "1"
		)
		(instances
			(project "sodimm-ddr5-tester"
				(path ""
					(reference "#PWR0266")
					(unit 1)
				)
			)
		)
	)
	(symbol
		(lib_id "antmicropower:+1V1")
		(at 216.535 58.42 0)
		(unit 1)
		(exclude_from_sim no)
		(in_bom yes)
		(on_board yes)
		(dnp no)
		(fields_autoplaced yes)
		(property "Reference" "#PWR0274"
			(at 216.535 62.23 0)
			(effects
				(font
					(size 1.27 1.27)
				)
				(hide yes)
			)
		)
		(property "Value" "+1V1"
			(at 216.535 54.864 0)
			(effects
				(font
					(size 1.27 1.27)
				)
			)
		)
		(property "Footprint" ""
			(at 216.535 58.42 0)
			(effects
				(font
					(size 1.27 1.27)
				)
				(hide yes)
			)
		)
		(property "Datasheet" ""
			(at 216.535 58.42 0)
			(effects
				(font
					(size 1.27 1.27)
				)
				(hide yes)
			)
		)
		(property "Description" ""
			(at 216.535 58.42 0)
			(effects
				(font
					(size 1.27 1.27)
				)
			)
		)
		(pin "1"
		)
		(instances
			(project "sodimm-ddr5-tester"
				(path ""
					(reference "#PWR0274")
					(unit 1)
				)
			)
		)
	)
	(symbol
		(lib_id "antmicropower:+1V1")
		(at 315.595 58.42 0)
		(unit 1)
		(exclude_from_sim no)
		(in_bom yes)
		(on_board yes)
		(dnp no)
		(fields_autoplaced yes)
		(property "Reference" "#PWR0278"
			(at 315.595 62.23 0)
			(effects
				(font
					(size 1.27 1.27)
				)
				(hide yes)
			)
		)
		(property "Value" "+1V1"
			(at 315.595 54.864 0)
			(effects
				(font
					(size 1.27 1.27)
				)
			)
		)
		(property "Footprint" ""
			(at 315.595 58.42 0)
			(effects
				(font
					(size 1.27 1.27)
				)
				(hide yes)
			)
		)
		(property "Datasheet" ""
			(at 315.595 58.42 0)
			(effects
				(font
					(size 1.27 1.27)
				)
				(hide yes)
			)
		)
		(property "Description" ""
			(at 315.595 58.42 0)
			(effects
				(font
					(size 1.27 1.27)
				)
			)
		)
		(pin "1"
		)
		(instances
			(project "sodimm-ddr5-tester"
				(path ""
					(reference "#PWR0278")
					(unit 1)
				)
			)
		)
	)
)
